FILE_TYPE = MACRO_DRAWING;
SET COLOR_WIRE YELLOW;
SET COLOR_PROP ORANGE;
SET COLOR_DOT WHITE;
SET COLOR_ARC YELLOW;
SET COLOR_BODY GREEN;
SET COLOR_NOTE PURPLE;
SET PROP_DISPLAY VALUE;
SET PAGE_NUMBER P167;
FORCEADD OFFPAGE..1
(1700 3600);
FORCEPROP 2 LAST $XR0 61 
J 0
(1479 3600);
DISPLAY 0.638298 (1479 3600);
PAINT MONO (1479 3600);
FORCEPROP 2 LAST CDS_LIB standard
J 0
(1700 3600);
DISPLAY INVISIBLE (1700 3600);
FORCEPROP 1 LAST OFFPAGE TRUE
J 0
(2025 3475);
DISPLAY 0.872340 (2025 3475);
DISPLAY INVISIBLE (2025 3475);
FORCEPROP 1 LAST COMMENT_BODY TRUE
J 0
(1825 3500);
DISPLAY 0.872340 (1825 3500);
PAINT GREEN (1825 3500);
DISPLAY INVISIBLE (1825 3500);
FORCEPROP 2 LAST PATH I107
J 0
(1750 3675);
DISPLAY 1.021277 (1750 3675);
DISPLAY INVISIBLE (1750 3675);
FORCEADD OFFPAGE..1
(1700 3650);
FORCEPROP 2 LAST $XR0 61 
J 0
(1479 3650);
DISPLAY 0.638298 (1479 3650);
PAINT MONO (1479 3650);
FORCEPROP 2 LAST CDS_LIB standard
J 0
(1700 3650);
DISPLAY INVISIBLE (1700 3650);
FORCEPROP 1 LAST OFFPAGE TRUE
J 0
(2025 3525);
DISPLAY 0.872340 (2025 3525);
DISPLAY INVISIBLE (2025 3525);
FORCEPROP 1 LAST COMMENT_BODY TRUE
J 0
(1825 3550);
DISPLAY 0.872340 (1825 3550);
PAINT GREEN (1825 3550);
DISPLAY INVISIBLE (1825 3550);
FORCEPROP 2 LAST PATH I108
J 0
(1750 3725);
DISPLAY 1.021277 (1750 3725);
DISPLAY INVISIBLE (1750 3725);
FORCEADD TAP..1
R 2
(2650 200);
FORCEPROP 3 LASTPIN (2700 200) SIG_NAME P5E_CPU1_PE2_TX_DP<0>
J 0
(2710 210);
DISPLAY 0.659574 (2710 210);
PAINT MONO (2710 210);
DISPLAY INVISIBLE (2710 210);
FORCEPROP 1 LASTPIN (2700 200) BN 0
J 2
(2712 208);
DISPLAY 0.680851 (2712 208);
PAINT GREEN (2712 208);
FORCEPROP 2 LAST CDS_LIB standard
J 0
(2650 200);
DISPLAY INVISIBLE (2650 200);
FORCEPROP 1 LAST BODY_TYPE PLUMBING
J 2
(2650 250);
DISPLAY 0.872340 (2650 250);
PAINT GREEN (2650 250);
DISPLAY INVISIBLE (2650 250);
FORCEPROP 1 LAST HDL_TAP TRUE
J 2
(2325 75);
DISPLAY 0.872340 (2325 75);
DISPLAY INVISIBLE (2325 75);
FORCEPROP 1 LAST PATH I109
J 2
(2652 200);
DISPLAY 0.872340 (2652 200);
PAINT GREEN (2652 200);
DISPLAY INVISIBLE (2652 200);
FORCEADD TAP..1
R 2
(2650 400);
FORCEPROP 3 LASTPIN (2700 400) SIG_NAME P5E_CPU1_PE2_TX_DP<1>
J 0
(2710 410);
DISPLAY 0.659574 (2710 410);
PAINT MONO (2710 410);
DISPLAY INVISIBLE (2710 410);
FORCEPROP 1 LASTPIN (2700 400) BN 1
J 2
(2712 408);
DISPLAY 0.680851 (2712 408);
PAINT GREEN (2712 408);
FORCEPROP 2 LAST CDS_LIB standard
J 0
(2650 400);
DISPLAY INVISIBLE (2650 400);
FORCEPROP 1 LAST BODY_TYPE PLUMBING
J 2
(2650 450);
DISPLAY 0.872340 (2650 450);
PAINT GREEN (2650 450);
DISPLAY INVISIBLE (2650 450);
FORCEPROP 1 LAST HDL_TAP TRUE
J 2
(2325 275);
DISPLAY 0.872340 (2325 275);
DISPLAY INVISIBLE (2325 275);
FORCEPROP 1 LAST PATH I110
J 2
(2652 400);
DISPLAY 0.872340 (2652 400);
PAINT GREEN (2652 400);
DISPLAY INVISIBLE (2652 400);
FORCEADD TAP..1
R 2
(2650 600);
FORCEPROP 3 LASTPIN (2700 600) SIG_NAME P5E_CPU1_PE2_TX_DP<2>
J 0
(2710 610);
DISPLAY 0.659574 (2710 610);
PAINT MONO (2710 610);
DISPLAY INVISIBLE (2710 610);
FORCEPROP 1 LASTPIN (2700 600) BN 2
J 2
(2712 608);
DISPLAY 0.680851 (2712 608);
PAINT GREEN (2712 608);
FORCEPROP 2 LAST CDS_LIB standard
J 0
(2650 600);
DISPLAY INVISIBLE (2650 600);
FORCEPROP 1 LAST BODY_TYPE PLUMBING
J 2
(2650 650);
DISPLAY 0.872340 (2650 650);
PAINT GREEN (2650 650);
DISPLAY INVISIBLE (2650 650);
FORCEPROP 1 LAST HDL_TAP TRUE
J 2
(2325 475);
DISPLAY 0.872340 (2325 475);
DISPLAY INVISIBLE (2325 475);
FORCEPROP 1 LAST PATH I111
J 2
(2652 600);
DISPLAY 0.872340 (2652 600);
PAINT GREEN (2652 600);
DISPLAY INVISIBLE (2652 600);
FORCEADD TAP..1
R 2
(2650 800);
FORCEPROP 3 LASTPIN (2700 800) SIG_NAME P5E_CPU1_PE2_TX_DP<3>
J 0
(2710 810);
DISPLAY 0.659574 (2710 810);
PAINT MONO (2710 810);
DISPLAY INVISIBLE (2710 810);
FORCEPROP 1 LASTPIN (2700 800) BN 3
J 2
(2712 808);
DISPLAY 0.680851 (2712 808);
PAINT GREEN (2712 808);
FORCEPROP 2 LAST CDS_LIB standard
J 0
(2650 800);
DISPLAY INVISIBLE (2650 800);
FORCEPROP 1 LAST BODY_TYPE PLUMBING
J 2
(2650 850);
DISPLAY 0.872340 (2650 850);
PAINT GREEN (2650 850);
DISPLAY INVISIBLE (2650 850);
FORCEPROP 1 LAST HDL_TAP TRUE
J 2
(2325 675);
DISPLAY 0.872340 (2325 675);
DISPLAY INVISIBLE (2325 675);
FORCEPROP 1 LAST PATH I112
J 2
(2652 800);
DISPLAY 0.872340 (2652 800);
PAINT GREEN (2652 800);
DISPLAY INVISIBLE (2652 800);
FORCEADD TAP..1
R 2
(2650 1000);
FORCEPROP 3 LASTPIN (2700 1000) SIG_NAME P5E_CPU1_PE2_TX_DP<4>
J 0
(2710 1010);
DISPLAY 0.659574 (2710 1010);
PAINT MONO (2710 1010);
DISPLAY INVISIBLE (2710 1010);
FORCEPROP 1 LASTPIN (2700 1000) BN 4
J 2
(2712 1008);
DISPLAY 0.680851 (2712 1008);
PAINT GREEN (2712 1008);
FORCEPROP 2 LAST CDS_LIB standard
J 0
(2650 1000);
DISPLAY INVISIBLE (2650 1000);
FORCEPROP 1 LAST BODY_TYPE PLUMBING
J 2
(2650 1050);
DISPLAY 0.872340 (2650 1050);
PAINT GREEN (2650 1050);
DISPLAY INVISIBLE (2650 1050);
FORCEPROP 1 LAST HDL_TAP TRUE
J 2
(2325 875);
DISPLAY 0.872340 (2325 875);
DISPLAY INVISIBLE (2325 875);
FORCEPROP 1 LAST PATH I113
J 2
(2652 1000);
DISPLAY 0.872340 (2652 1000);
PAINT GREEN (2652 1000);
DISPLAY INVISIBLE (2652 1000);
FORCEADD TAP..1
R 2
(2650 1200);
FORCEPROP 3 LASTPIN (2700 1200) SIG_NAME P5E_CPU1_PE2_TX_DP<5>
J 0
(2710 1210);
DISPLAY 0.659574 (2710 1210);
PAINT MONO (2710 1210);
DISPLAY INVISIBLE (2710 1210);
FORCEPROP 1 LASTPIN (2700 1200) BN 5
J 2
(2712 1208);
DISPLAY 0.680851 (2712 1208);
PAINT GREEN (2712 1208);
FORCEPROP 2 LAST CDS_LIB standard
J 0
(2650 1200);
DISPLAY INVISIBLE (2650 1200);
FORCEPROP 1 LAST BODY_TYPE PLUMBING
J 2
(2650 1250);
DISPLAY 0.872340 (2650 1250);
PAINT GREEN (2650 1250);
DISPLAY INVISIBLE (2650 1250);
FORCEPROP 1 LAST HDL_TAP TRUE
J 2
(2325 1075);
DISPLAY 0.872340 (2325 1075);
DISPLAY INVISIBLE (2325 1075);
FORCEPROP 1 LAST PATH I114
J 2
(2652 1200);
DISPLAY 0.872340 (2652 1200);
PAINT GREEN (2652 1200);
DISPLAY INVISIBLE (2652 1200);
FORCEADD TAP..1
R 2
(2650 1400);
FORCEPROP 3 LASTPIN (2700 1400) SIG_NAME P5E_CPU1_PE2_TX_DP<6>
J 0
(2710 1410);
DISPLAY 0.659574 (2710 1410);
PAINT MONO (2710 1410);
DISPLAY INVISIBLE (2710 1410);
FORCEPROP 1 LASTPIN (2700 1400) BN 6
J 2
(2712 1408);
DISPLAY 0.680851 (2712 1408);
PAINT GREEN (2712 1408);
FORCEPROP 2 LAST CDS_LIB standard
J 0
(2650 1400);
DISPLAY INVISIBLE (2650 1400);
FORCEPROP 1 LAST BODY_TYPE PLUMBING
J 2
(2650 1450);
DISPLAY 0.872340 (2650 1450);
PAINT GREEN (2650 1450);
DISPLAY INVISIBLE (2650 1450);
FORCEPROP 1 LAST HDL_TAP TRUE
J 2
(2325 1275);
DISPLAY 0.872340 (2325 1275);
DISPLAY INVISIBLE (2325 1275);
FORCEPROP 1 LAST PATH I115
J 2
(2652 1400);
DISPLAY 0.872340 (2652 1400);
PAINT GREEN (2652 1400);
DISPLAY INVISIBLE (2652 1400);
FORCEADD TAP..1
R 2
(2650 1600);
FORCEPROP 3 LASTPIN (2700 1600) SIG_NAME P5E_CPU1_PE2_TX_DP<7>
J 0
(2710 1610);
DISPLAY 0.659574 (2710 1610);
PAINT MONO (2710 1610);
DISPLAY INVISIBLE (2710 1610);
FORCEPROP 1 LASTPIN (2700 1600) BN 7
J 2
(2712 1608);
DISPLAY 0.680851 (2712 1608);
PAINT GREEN (2712 1608);
FORCEPROP 2 LAST CDS_LIB standard
J 0
(2650 1600);
DISPLAY INVISIBLE (2650 1600);
FORCEPROP 1 LAST BODY_TYPE PLUMBING
J 2
(2650 1650);
DISPLAY 0.872340 (2650 1650);
PAINT GREEN (2650 1650);
DISPLAY INVISIBLE (2650 1650);
FORCEPROP 1 LAST HDL_TAP TRUE
J 2
(2325 1475);
DISPLAY 0.872340 (2325 1475);
DISPLAY INVISIBLE (2325 1475);
FORCEPROP 1 LAST PATH I116
J 2
(2652 1600);
DISPLAY 0.872340 (2652 1600);
PAINT GREEN (2652 1600);
DISPLAY INVISIBLE (2652 1600);
FORCEADD TAP..1
R 2
(2900 250);
FORCEPROP 3 LASTPIN (2950 250) SIG_NAME P5E_CPU1_PE2_TX_DN<0>
J 0
(2960 260);
DISPLAY 0.659574 (2960 260);
PAINT MONO (2960 260);
DISPLAY INVISIBLE (2960 260);
FORCEPROP 1 LASTPIN (2950 250) BN 0
J 2
(2962 258);
DISPLAY 0.680851 (2962 258);
PAINT GREEN (2962 258);
FORCEPROP 2 LAST CDS_LIB standard
J 0
(2900 250);
DISPLAY INVISIBLE (2900 250);
FORCEPROP 1 LAST BODY_TYPE PLUMBING
J 2
(2900 300);
DISPLAY 0.872340 (2900 300);
PAINT GREEN (2900 300);
DISPLAY INVISIBLE (2900 300);
FORCEPROP 1 LAST HDL_TAP TRUE
J 2
(2575 125);
DISPLAY 0.872340 (2575 125);
DISPLAY INVISIBLE (2575 125);
FORCEPROP 1 LAST PATH I117
J 2
(2902 250);
DISPLAY 0.872340 (2902 250);
PAINT GREEN (2902 250);
DISPLAY INVISIBLE (2902 250);
FORCEADD TAP..1
R 2
(2900 450);
FORCEPROP 3 LASTPIN (2950 450) SIG_NAME P5E_CPU1_PE2_TX_DN<1>
J 0
(2960 460);
DISPLAY 0.659574 (2960 460);
PAINT MONO (2960 460);
DISPLAY INVISIBLE (2960 460);
FORCEPROP 1 LASTPIN (2950 450) BN 1
J 2
(2962 458);
DISPLAY 0.680851 (2962 458);
PAINT GREEN (2962 458);
FORCEPROP 2 LAST CDS_LIB standard
J 0
(2900 450);
DISPLAY INVISIBLE (2900 450);
FORCEPROP 1 LAST BODY_TYPE PLUMBING
J 2
(2900 500);
DISPLAY 0.872340 (2900 500);
PAINT GREEN (2900 500);
DISPLAY INVISIBLE (2900 500);
FORCEPROP 1 LAST HDL_TAP TRUE
J 2
(2575 325);
DISPLAY 0.872340 (2575 325);
DISPLAY INVISIBLE (2575 325);
FORCEPROP 1 LAST PATH I118
J 2
(2902 450);
DISPLAY 0.872340 (2902 450);
PAINT GREEN (2902 450);
DISPLAY INVISIBLE (2902 450);
FORCEADD TAP..1
R 2
(2900 650);
FORCEPROP 3 LASTPIN (2950 650) SIG_NAME P5E_CPU1_PE2_TX_DN<2>
J 0
(2960 660);
DISPLAY 0.659574 (2960 660);
PAINT MONO (2960 660);
DISPLAY INVISIBLE (2960 660);
FORCEPROP 1 LASTPIN (2950 650) BN 2
J 2
(2962 658);
DISPLAY 0.680851 (2962 658);
PAINT GREEN (2962 658);
FORCEPROP 2 LAST CDS_LIB standard
J 0
(2900 650);
DISPLAY INVISIBLE (2900 650);
FORCEPROP 1 LAST BODY_TYPE PLUMBING
J 2
(2900 700);
DISPLAY 0.872340 (2900 700);
PAINT GREEN (2900 700);
DISPLAY INVISIBLE (2900 700);
FORCEPROP 1 LAST HDL_TAP TRUE
J 2
(2575 525);
DISPLAY 0.872340 (2575 525);
DISPLAY INVISIBLE (2575 525);
FORCEPROP 1 LAST PATH I119
J 2
(2902 650);
DISPLAY 0.872340 (2902 650);
PAINT GREEN (2902 650);
DISPLAY INVISIBLE (2902 650);
FORCEADD TAP..1
R 2
(2900 850);
FORCEPROP 3 LASTPIN (2950 850) SIG_NAME P5E_CPU1_PE2_TX_DN<3>
J 0
(2960 860);
DISPLAY 0.659574 (2960 860);
PAINT MONO (2960 860);
DISPLAY INVISIBLE (2960 860);
FORCEPROP 1 LASTPIN (2950 850) BN 3
J 2
(2962 858);
DISPLAY 0.680851 (2962 858);
PAINT GREEN (2962 858);
FORCEPROP 2 LAST CDS_LIB standard
J 0
(2900 850);
DISPLAY INVISIBLE (2900 850);
FORCEPROP 1 LAST BODY_TYPE PLUMBING
J 2
(2900 900);
DISPLAY 0.872340 (2900 900);
PAINT GREEN (2900 900);
DISPLAY INVISIBLE (2900 900);
FORCEPROP 1 LAST HDL_TAP TRUE
J 2
(2575 725);
DISPLAY 0.872340 (2575 725);
DISPLAY INVISIBLE (2575 725);
FORCEPROP 1 LAST PATH I120
J 2
(2902 850);
DISPLAY 0.872340 (2902 850);
PAINT GREEN (2902 850);
DISPLAY INVISIBLE (2902 850);
FORCEADD TAP..1
R 2
(2900 1050);
FORCEPROP 3 LASTPIN (2950 1050) SIG_NAME P5E_CPU1_PE2_TX_DN<4>
J 0
(2960 1060);
DISPLAY 0.659574 (2960 1060);
PAINT MONO (2960 1060);
DISPLAY INVISIBLE (2960 1060);
FORCEPROP 1 LASTPIN (2950 1050) BN 4
J 2
(2962 1058);
DISPLAY 0.680851 (2962 1058);
PAINT GREEN (2962 1058);
FORCEPROP 2 LAST CDS_LIB standard
J 0
(2900 1050);
DISPLAY INVISIBLE (2900 1050);
FORCEPROP 1 LAST BODY_TYPE PLUMBING
J 2
(2900 1100);
DISPLAY 0.872340 (2900 1100);
PAINT GREEN (2900 1100);
DISPLAY INVISIBLE (2900 1100);
FORCEPROP 1 LAST HDL_TAP TRUE
J 2
(2575 925);
DISPLAY 0.872340 (2575 925);
DISPLAY INVISIBLE (2575 925);
FORCEPROP 1 LAST PATH I121
J 2
(2902 1050);
DISPLAY 0.872340 (2902 1050);
PAINT GREEN (2902 1050);
DISPLAY INVISIBLE (2902 1050);
FORCEADD Q_CAP_DIFFBUS..2
R 2
(3625 200);
FORCEPROP 1 LAST PART_NUMBER SP_CH4221MEE01
J 2
(3509 288);
DISPLAY 0.574468 (3509 288);
PAINT GREEN (3509 288);
DISPLAY INVISIBLE (3509 288);
FORCEPROP 2 LAST VALUE DIFF BUS_0.22UF
J 2
(3475 200);
DISPLAY 0.553191 (3475 200);
FORCEPROP 1 LAST $LOCATION C773
J 2
(3859 217);
DISPLAY 0.723404 (3859 217);
PAINT GREEN (3859 217);
FORCEPROP 2 LASTPIN (3700 200) $PN 1
J 0
(3710 210);
DISPLAY 0.808511 (3710 210);
FORCEPROP 2 LASTPIN (3550 200) $PN 2
J 2
(3540 210);
DISPLAY 0.808511 (3540 210);
FORCEPROP 1 LAST PIN_NAMES_ROTATE TRUE
J 2
(3625 200);
DISPLAY 0.489362 (3625 200);
PAINT GREEN (3625 200);
DISPLAY INVISIBLE (3625 200);
FORCEPROP 2 LAST CDS_LIB pure_quanta
J 2
(3625 200);
DISPLAY INVISIBLE (3625 200);
FORCEPROP 1 LAST CDS_LMAN_SYM_OUTLINE -25,50,25,-50
J 2
(3625 200);
DISPLAY 0.468085 (3625 200);
PAINT GREEN (3625 200);
DISPLAY INVISIBLE (3625 200);
FORCEPROP 2 LAST VOLTAGE 6.3V
J 2
(3275 250);
DISPLAY 0.553191 (3275 250);
DISPLAY INVISIBLE (3275 250);
FORCEPROP 1 LAST MATERIAL X6S
J 2
(3634 279);
DISPLAY 0.574468 (3634 279);
PAINT GREEN (3634 279);
DISPLAY INVISIBLE (3634 279);
FORCEPROP 2 LAST PACK_TYPE C0201
J 2
(3450 250);
DISPLAY 0.553191 (3450 250);
DISPLAY INVISIBLE (3450 250);
FORCEPROP 2 LAST TOLERANCE 20%
J 2
(3550 250);
DISPLAY 0.553191 (3550 250);
DISPLAY INVISIBLE (3550 250);
FORCEPROP 1 LAST PATH I122
J 2
(3625 200);
DISPLAY 0.723404 (3625 200);
DISPLAY INVISIBLE (3625 200);
FORCEPROP 1 LAST $LOCATION C773
J 0
(3875 275);
DISPLAY 1.021277 (3875 275);
DISPLAY INVISIBLE (3875 275);
FORCEPROP 2 LAST CDS_LOCATION C773
J 0
(3875 275);
DISPLAY 1.021277 (3875 275);
DISPLAY INVISIBLE (3875 275);
FORCEPROP 2 LAST $SEC 1
J 2
(3800 275);
DISPLAY 0.680851 (3800 275);
PAINT MONO (3800 275);
DISPLAY INVISIBLE (3800 275);
FORCEPROP 2 LAST CDS_SEC 1
J 2
(3800 275);
DISPLAY 0.680851 (3800 275);
DISPLAY INVISIBLE (3800 275);
FORCEADD Q_CAP_DIFFBUS..2
R 2
(3625 250);
FORCEPROP 1 LAST PART_NUMBER SP_CH4221MEE01
J 2
(3509 338);
DISPLAY 0.574468 (3509 338);
PAINT GREEN (3509 338);
DISPLAY INVISIBLE (3509 338);
FORCEPROP 2 LAST VALUE DIFF BUS_0.22UF
J 2
(3475 250);
DISPLAY 0.553191 (3475 250);
FORCEPROP 1 LAST $LOCATION C772
J 2
(3859 267);
DISPLAY 0.723404 (3859 267);
PAINT GREEN (3859 267);
FORCEPROP 2 LASTPIN (3700 250) $PN 1
J 0
(3710 260);
DISPLAY 0.808511 (3710 260);
FORCEPROP 2 LASTPIN (3550 250) $PN 2
J 2
(3540 260);
DISPLAY 0.808511 (3540 260);
FORCEPROP 1 LAST PIN_NAMES_ROTATE TRUE
J 2
(3625 250);
DISPLAY 0.489362 (3625 250);
PAINT GREEN (3625 250);
DISPLAY INVISIBLE (3625 250);
FORCEPROP 2 LAST CDS_LIB pure_quanta
J 2
(3625 250);
DISPLAY INVISIBLE (3625 250);
FORCEPROP 1 LAST CDS_LMAN_SYM_OUTLINE -25,50,25,-50
J 2
(3625 250);
DISPLAY 0.468085 (3625 250);
PAINT GREEN (3625 250);
DISPLAY INVISIBLE (3625 250);
FORCEPROP 2 LAST VOLTAGE 6.3V
J 2
(3275 300);
DISPLAY 0.553191 (3275 300);
DISPLAY INVISIBLE (3275 300);
FORCEPROP 1 LAST MATERIAL X6S
J 2
(3634 329);
DISPLAY 0.574468 (3634 329);
PAINT GREEN (3634 329);
DISPLAY INVISIBLE (3634 329);
FORCEPROP 2 LAST PACK_TYPE C0201
J 2
(3450 300);
DISPLAY 0.553191 (3450 300);
DISPLAY INVISIBLE (3450 300);
FORCEPROP 2 LAST TOLERANCE 20%
J 2
(3550 300);
DISPLAY 0.553191 (3550 300);
DISPLAY INVISIBLE (3550 300);
FORCEPROP 1 LAST PATH I123
J 2
(3625 250);
DISPLAY 0.723404 (3625 250);
DISPLAY INVISIBLE (3625 250);
FORCEPROP 1 LAST $LOCATION C772
J 0
(3875 325);
DISPLAY 1.021277 (3875 325);
DISPLAY INVISIBLE (3875 325);
FORCEPROP 2 LAST CDS_LOCATION C772
J 0
(3875 325);
DISPLAY 1.021277 (3875 325);
DISPLAY INVISIBLE (3875 325);
FORCEPROP 2 LAST $SEC 1
J 2
(3800 325);
DISPLAY 0.680851 (3800 325);
PAINT MONO (3800 325);
DISPLAY INVISIBLE (3800 325);
FORCEPROP 2 LAST CDS_SEC 1
J 2
(3800 325);
DISPLAY 0.680851 (3800 325);
DISPLAY INVISIBLE (3800 325);
FORCEADD Q_CAP_DIFFBUS..2
R 2
(3625 400);
FORCEPROP 1 LAST PART_NUMBER SP_CH4221MEE01
J 2
(3509 488);
DISPLAY 0.574468 (3509 488);
PAINT GREEN (3509 488);
DISPLAY INVISIBLE (3509 488);
FORCEPROP 2 LAST VALUE DIFF BUS_0.22UF
J 2
(3475 400);
DISPLAY 0.553191 (3475 400);
FORCEPROP 1 LAST $LOCATION C771
J 2
(3859 417);
DISPLAY 0.723404 (3859 417);
PAINT GREEN (3859 417);
FORCEPROP 2 LASTPIN (3700 400) $PN 1
J 0
(3710 410);
DISPLAY 0.808511 (3710 410);
FORCEPROP 2 LASTPIN (3550 400) $PN 2
J 2
(3540 410);
DISPLAY 0.808511 (3540 410);
FORCEPROP 1 LAST PIN_NAMES_ROTATE TRUE
J 2
(3625 400);
DISPLAY 0.489362 (3625 400);
PAINT GREEN (3625 400);
DISPLAY INVISIBLE (3625 400);
FORCEPROP 2 LAST CDS_LIB pure_quanta
J 2
(3625 400);
DISPLAY INVISIBLE (3625 400);
FORCEPROP 1 LAST CDS_LMAN_SYM_OUTLINE -25,50,25,-50
J 2
(3625 400);
DISPLAY 0.468085 (3625 400);
PAINT GREEN (3625 400);
DISPLAY INVISIBLE (3625 400);
FORCEPROP 2 LAST VOLTAGE 6.3V
J 2
(3275 450);
DISPLAY 0.553191 (3275 450);
DISPLAY INVISIBLE (3275 450);
FORCEPROP 1 LAST MATERIAL X6S
J 2
(3634 479);
DISPLAY 0.574468 (3634 479);
PAINT GREEN (3634 479);
DISPLAY INVISIBLE (3634 479);
FORCEPROP 2 LAST PACK_TYPE C0201
J 2
(3450 450);
DISPLAY 0.553191 (3450 450);
DISPLAY INVISIBLE (3450 450);
FORCEPROP 2 LAST TOLERANCE 20%
J 2
(3550 450);
DISPLAY 0.553191 (3550 450);
DISPLAY INVISIBLE (3550 450);
FORCEPROP 1 LAST PATH I124
J 2
(3625 400);
DISPLAY 0.723404 (3625 400);
DISPLAY INVISIBLE (3625 400);
FORCEPROP 1 LAST $LOCATION C771
J 0
(3875 475);
DISPLAY 1.021277 (3875 475);
DISPLAY INVISIBLE (3875 475);
FORCEPROP 2 LAST CDS_LOCATION C771
J 0
(3875 475);
DISPLAY 1.021277 (3875 475);
DISPLAY INVISIBLE (3875 475);
FORCEPROP 2 LAST $SEC 1
J 2
(3800 475);
DISPLAY 0.680851 (3800 475);
PAINT MONO (3800 475);
DISPLAY INVISIBLE (3800 475);
FORCEPROP 2 LAST CDS_SEC 1
J 2
(3800 475);
DISPLAY 0.680851 (3800 475);
DISPLAY INVISIBLE (3800 475);
FORCEADD Q_CAP_DIFFBUS..2
R 2
(3625 450);
FORCEPROP 1 LAST PART_NUMBER SP_CH4221MEE01
J 2
(3509 538);
DISPLAY 0.574468 (3509 538);
PAINT GREEN (3509 538);
DISPLAY INVISIBLE (3509 538);
FORCEPROP 2 LAST VALUE DIFF BUS_0.22UF
J 2
(3475 450);
DISPLAY 0.553191 (3475 450);
FORCEPROP 1 LAST $LOCATION C770
J 2
(3859 467);
DISPLAY 0.723404 (3859 467);
PAINT GREEN (3859 467);
FORCEPROP 2 LASTPIN (3700 450) $PN 1
J 0
(3710 460);
DISPLAY 0.808511 (3710 460);
FORCEPROP 2 LASTPIN (3550 450) $PN 2
J 2
(3540 460);
DISPLAY 0.808511 (3540 460);
FORCEPROP 1 LAST PIN_NAMES_ROTATE TRUE
J 2
(3625 450);
DISPLAY 0.489362 (3625 450);
PAINT GREEN (3625 450);
DISPLAY INVISIBLE (3625 450);
FORCEPROP 1 LAST CDS_LMAN_SYM_OUTLINE -25,50,25,-50
J 2
(3625 450);
DISPLAY 0.468085 (3625 450);
PAINT GREEN (3625 450);
DISPLAY INVISIBLE (3625 450);
FORCEPROP 2 LAST CDS_LIB pure_quanta
J 2
(3625 450);
DISPLAY INVISIBLE (3625 450);
FORCEPROP 2 LAST VOLTAGE 6.3V
J 2
(3275 500);
DISPLAY 0.553191 (3275 500);
DISPLAY INVISIBLE (3275 500);
FORCEPROP 1 LAST MATERIAL X6S
J 2
(3634 529);
DISPLAY 0.574468 (3634 529);
PAINT GREEN (3634 529);
DISPLAY INVISIBLE (3634 529);
FORCEPROP 2 LAST PACK_TYPE C0201
J 2
(3450 500);
DISPLAY 0.553191 (3450 500);
DISPLAY INVISIBLE (3450 500);
FORCEPROP 2 LAST TOLERANCE 20%
J 2
(3550 500);
DISPLAY 0.553191 (3550 500);
DISPLAY INVISIBLE (3550 500);
FORCEPROP 1 LAST PATH I125
J 2
(3625 450);
DISPLAY 0.723404 (3625 450);
DISPLAY INVISIBLE (3625 450);
FORCEPROP 1 LAST $LOCATION C770
J 0
(3875 525);
DISPLAY 1.021277 (3875 525);
DISPLAY INVISIBLE (3875 525);
FORCEPROP 2 LAST CDS_LOCATION C770
J 0
(3875 525);
DISPLAY 1.021277 (3875 525);
DISPLAY INVISIBLE (3875 525);
FORCEPROP 2 LAST $SEC 1
J 2
(3800 525);
DISPLAY 0.680851 (3800 525);
PAINT MONO (3800 525);
DISPLAY INVISIBLE (3800 525);
FORCEPROP 2 LAST CDS_SEC 1
J 2
(3800 525);
DISPLAY 0.680851 (3800 525);
DISPLAY INVISIBLE (3800 525);
FORCEADD Q_CAP_DIFFBUS..2
R 2
(3625 600);
FORCEPROP 1 LAST PART_NUMBER SP_CH4221MEE01
J 2
(3509 688);
DISPLAY 0.574468 (3509 688);
PAINT GREEN (3509 688);
DISPLAY INVISIBLE (3509 688);
FORCEPROP 2 LAST VALUE DIFF BUS_0.22UF
J 2
(3475 600);
DISPLAY 0.553191 (3475 600);
FORCEPROP 1 LAST $LOCATION C769
J 2
(3859 617);
DISPLAY 0.723404 (3859 617);
PAINT GREEN (3859 617);
FORCEPROP 2 LASTPIN (3700 600) $PN 1
J 0
(3710 610);
DISPLAY 0.808511 (3710 610);
FORCEPROP 2 LASTPIN (3550 600) $PN 2
J 2
(3540 610);
DISPLAY 0.808511 (3540 610);
FORCEPROP 1 LAST PIN_NAMES_ROTATE TRUE
J 2
(3625 600);
DISPLAY 0.489362 (3625 600);
PAINT GREEN (3625 600);
DISPLAY INVISIBLE (3625 600);
FORCEPROP 2 LAST CDS_LIB pure_quanta
J 2
(3625 600);
DISPLAY INVISIBLE (3625 600);
FORCEPROP 1 LAST CDS_LMAN_SYM_OUTLINE -25,50,25,-50
J 2
(3625 600);
DISPLAY 0.468085 (3625 600);
PAINT GREEN (3625 600);
DISPLAY INVISIBLE (3625 600);
FORCEPROP 2 LAST VOLTAGE 6.3V
J 2
(3275 650);
DISPLAY 0.553191 (3275 650);
DISPLAY INVISIBLE (3275 650);
FORCEPROP 1 LAST MATERIAL X6S
J 2
(3634 679);
DISPLAY 0.574468 (3634 679);
PAINT GREEN (3634 679);
DISPLAY INVISIBLE (3634 679);
FORCEPROP 2 LAST PACK_TYPE C0201
J 2
(3450 650);
DISPLAY 0.553191 (3450 650);
DISPLAY INVISIBLE (3450 650);
FORCEPROP 2 LAST TOLERANCE 20%
J 2
(3550 650);
DISPLAY 0.553191 (3550 650);
DISPLAY INVISIBLE (3550 650);
FORCEPROP 1 LAST PATH I126
J 2
(3625 600);
DISPLAY 0.723404 (3625 600);
DISPLAY INVISIBLE (3625 600);
FORCEPROP 1 LAST $LOCATION C769
J 0
(3875 675);
DISPLAY 1.021277 (3875 675);
DISPLAY INVISIBLE (3875 675);
FORCEPROP 2 LAST CDS_LOCATION C769
J 0
(3875 675);
DISPLAY 1.021277 (3875 675);
DISPLAY INVISIBLE (3875 675);
FORCEPROP 2 LAST $SEC 1
J 2
(3800 675);
DISPLAY 0.680851 (3800 675);
PAINT MONO (3800 675);
DISPLAY INVISIBLE (3800 675);
FORCEPROP 2 LAST CDS_SEC 1
J 2
(3800 675);
DISPLAY 0.680851 (3800 675);
DISPLAY INVISIBLE (3800 675);
FORCEADD Q_CAP_DIFFBUS..2
R 2
(3625 650);
FORCEPROP 1 LAST PART_NUMBER SP_CH4221MEE01
J 2
(3509 738);
DISPLAY 0.574468 (3509 738);
PAINT GREEN (3509 738);
DISPLAY INVISIBLE (3509 738);
FORCEPROP 2 LAST VALUE DIFF BUS_0.22UF
J 2
(3475 650);
DISPLAY 0.553191 (3475 650);
FORCEPROP 1 LAST $LOCATION C768
J 2
(3859 667);
DISPLAY 0.723404 (3859 667);
PAINT GREEN (3859 667);
FORCEPROP 2 LASTPIN (3700 650) $PN 1
J 0
(3710 660);
DISPLAY 0.808511 (3710 660);
FORCEPROP 2 LASTPIN (3550 650) $PN 2
J 2
(3540 660);
DISPLAY 0.808511 (3540 660);
FORCEPROP 1 LAST PIN_NAMES_ROTATE TRUE
J 2
(3625 650);
DISPLAY 0.489362 (3625 650);
PAINT GREEN (3625 650);
DISPLAY INVISIBLE (3625 650);
FORCEPROP 2 LAST CDS_LIB pure_quanta
J 2
(3625 650);
DISPLAY INVISIBLE (3625 650);
FORCEPROP 1 LAST CDS_LMAN_SYM_OUTLINE -25,50,25,-50
J 2
(3625 650);
DISPLAY 0.468085 (3625 650);
PAINT GREEN (3625 650);
DISPLAY INVISIBLE (3625 650);
FORCEPROP 2 LAST VOLTAGE 6.3V
J 2
(3275 700);
DISPLAY 0.553191 (3275 700);
DISPLAY INVISIBLE (3275 700);
FORCEPROP 1 LAST MATERIAL X6S
J 2
(3634 729);
DISPLAY 0.574468 (3634 729);
PAINT GREEN (3634 729);
DISPLAY INVISIBLE (3634 729);
FORCEPROP 2 LAST PACK_TYPE C0201
J 2
(3450 700);
DISPLAY 0.553191 (3450 700);
DISPLAY INVISIBLE (3450 700);
FORCEPROP 2 LAST TOLERANCE 20%
J 2
(3550 700);
DISPLAY 0.553191 (3550 700);
DISPLAY INVISIBLE (3550 700);
FORCEPROP 1 LAST PATH I127
J 2
(3625 650);
DISPLAY 0.723404 (3625 650);
DISPLAY INVISIBLE (3625 650);
FORCEPROP 1 LAST $LOCATION C768
J 0
(3875 725);
DISPLAY 1.021277 (3875 725);
DISPLAY INVISIBLE (3875 725);
FORCEPROP 2 LAST CDS_LOCATION C768
J 0
(3875 725);
DISPLAY 1.021277 (3875 725);
DISPLAY INVISIBLE (3875 725);
FORCEPROP 2 LAST $SEC 1
J 2
(3800 725);
DISPLAY 0.680851 (3800 725);
PAINT MONO (3800 725);
DISPLAY INVISIBLE (3800 725);
FORCEPROP 2 LAST CDS_SEC 1
J 2
(3800 725);
DISPLAY 0.680851 (3800 725);
DISPLAY INVISIBLE (3800 725);
FORCEADD Q_CAP_DIFFBUS..2
R 2
(3625 800);
FORCEPROP 1 LAST PART_NUMBER SP_CH4221MEE01
J 2
(3509 888);
DISPLAY 0.574468 (3509 888);
PAINT GREEN (3509 888);
DISPLAY INVISIBLE (3509 888);
FORCEPROP 2 LAST VALUE DIFF BUS_0.22UF
J 2
(3475 800);
DISPLAY 0.553191 (3475 800);
FORCEPROP 1 LAST $LOCATION C767
J 2
(3859 817);
DISPLAY 0.723404 (3859 817);
PAINT GREEN (3859 817);
FORCEPROP 2 LASTPIN (3700 800) $PN 1
J 0
(3710 810);
DISPLAY 0.808511 (3710 810);
FORCEPROP 2 LASTPIN (3550 800) $PN 2
J 2
(3540 810);
DISPLAY 0.808511 (3540 810);
FORCEPROP 1 LAST PIN_NAMES_ROTATE TRUE
J 2
(3625 800);
DISPLAY 0.489362 (3625 800);
PAINT GREEN (3625 800);
DISPLAY INVISIBLE (3625 800);
FORCEPROP 1 LAST CDS_LMAN_SYM_OUTLINE -25,50,25,-50
J 2
(3625 800);
DISPLAY 0.468085 (3625 800);
PAINT GREEN (3625 800);
DISPLAY INVISIBLE (3625 800);
FORCEPROP 2 LAST CDS_LIB pure_quanta
J 2
(3625 800);
DISPLAY INVISIBLE (3625 800);
FORCEPROP 2 LAST VOLTAGE 6.3V
J 2
(3275 850);
DISPLAY 0.553191 (3275 850);
DISPLAY INVISIBLE (3275 850);
FORCEPROP 1 LAST MATERIAL X6S
J 2
(3634 879);
DISPLAY 0.574468 (3634 879);
PAINT GREEN (3634 879);
DISPLAY INVISIBLE (3634 879);
FORCEPROP 2 LAST PACK_TYPE C0201
J 2
(3450 850);
DISPLAY 0.553191 (3450 850);
DISPLAY INVISIBLE (3450 850);
FORCEPROP 2 LAST TOLERANCE 20%
J 2
(3550 850);
DISPLAY 0.553191 (3550 850);
DISPLAY INVISIBLE (3550 850);
FORCEPROP 1 LAST PATH I128
J 2
(3625 800);
DISPLAY 0.723404 (3625 800);
DISPLAY INVISIBLE (3625 800);
FORCEPROP 1 LAST $LOCATION C767
J 0
(3875 875);
DISPLAY 1.021277 (3875 875);
DISPLAY INVISIBLE (3875 875);
FORCEPROP 2 LAST CDS_LOCATION C767
J 0
(3875 875);
DISPLAY 1.021277 (3875 875);
DISPLAY INVISIBLE (3875 875);
FORCEPROP 2 LAST $SEC 1
J 2
(3800 875);
DISPLAY 0.680851 (3800 875);
PAINT MONO (3800 875);
DISPLAY INVISIBLE (3800 875);
FORCEPROP 2 LAST CDS_SEC 1
J 2
(3800 875);
DISPLAY 0.680851 (3800 875);
DISPLAY INVISIBLE (3800 875);
FORCEADD Q_CAP_DIFFBUS..2
R 2
(3625 850);
FORCEPROP 1 LAST PART_NUMBER SP_CH4221MEE01
J 2
(3509 938);
DISPLAY 0.574468 (3509 938);
PAINT GREEN (3509 938);
DISPLAY INVISIBLE (3509 938);
FORCEPROP 2 LAST VALUE DIFF BUS_0.22UF
J 2
(3475 850);
DISPLAY 0.553191 (3475 850);
FORCEPROP 1 LAST $LOCATION C766
J 2
(3859 867);
DISPLAY 0.723404 (3859 867);
PAINT GREEN (3859 867);
FORCEPROP 2 LASTPIN (3700 850) $PN 1
J 0
(3710 860);
DISPLAY 0.808511 (3710 860);
FORCEPROP 2 LASTPIN (3550 850) $PN 2
J 2
(3540 860);
DISPLAY 0.808511 (3540 860);
FORCEPROP 1 LAST PIN_NAMES_ROTATE TRUE
J 2
(3625 850);
DISPLAY 0.489362 (3625 850);
PAINT GREEN (3625 850);
DISPLAY INVISIBLE (3625 850);
FORCEPROP 1 LAST CDS_LMAN_SYM_OUTLINE -25,50,25,-50
J 2
(3625 850);
DISPLAY 0.468085 (3625 850);
PAINT GREEN (3625 850);
DISPLAY INVISIBLE (3625 850);
FORCEPROP 2 LAST CDS_LIB pure_quanta
J 2
(3625 850);
DISPLAY INVISIBLE (3625 850);
FORCEPROP 2 LAST VOLTAGE 6.3V
J 2
(3275 900);
DISPLAY 0.553191 (3275 900);
DISPLAY INVISIBLE (3275 900);
FORCEPROP 1 LAST MATERIAL X6S
J 2
(3634 929);
DISPLAY 0.574468 (3634 929);
PAINT GREEN (3634 929);
DISPLAY INVISIBLE (3634 929);
FORCEPROP 2 LAST PACK_TYPE C0201
J 2
(3450 900);
DISPLAY 0.553191 (3450 900);
DISPLAY INVISIBLE (3450 900);
FORCEPROP 2 LAST TOLERANCE 20%
J 2
(3550 900);
DISPLAY 0.553191 (3550 900);
DISPLAY INVISIBLE (3550 900);
FORCEPROP 1 LAST PATH I129
J 2
(3625 850);
DISPLAY 0.723404 (3625 850);
DISPLAY INVISIBLE (3625 850);
FORCEPROP 1 LAST $LOCATION C766
J 0
(3875 925);
DISPLAY 1.021277 (3875 925);
DISPLAY INVISIBLE (3875 925);
FORCEPROP 2 LAST CDS_LOCATION C766
J 0
(3875 925);
DISPLAY 1.021277 (3875 925);
DISPLAY INVISIBLE (3875 925);
FORCEPROP 2 LAST $SEC 1
J 2
(3800 925);
DISPLAY 0.680851 (3800 925);
PAINT MONO (3800 925);
DISPLAY INVISIBLE (3800 925);
FORCEPROP 2 LAST CDS_SEC 1
J 2
(3800 925);
DISPLAY 0.680851 (3800 925);
DISPLAY INVISIBLE (3800 925);
FORCEADD Q_CAP_DIFFBUS..2
R 2
(3625 1050);
FORCEPROP 1 LAST PART_NUMBER SP_CH4221MEE01
J 2
(3509 1138);
DISPLAY 0.574468 (3509 1138);
PAINT GREEN (3509 1138);
DISPLAY INVISIBLE (3509 1138);
FORCEPROP 2 LAST VALUE DIFF BUS_0.22UF
J 2
(3475 1050);
DISPLAY 0.553191 (3475 1050);
FORCEPROP 1 LAST $LOCATION C764
J 2
(3859 1067);
DISPLAY 0.723404 (3859 1067);
PAINT GREEN (3859 1067);
FORCEPROP 2 LASTPIN (3700 1050) $PN 1
J 0
(3710 1060);
DISPLAY 0.808511 (3710 1060);
FORCEPROP 2 LASTPIN (3550 1050) $PN 2
J 2
(3540 1060);
DISPLAY 0.808511 (3540 1060);
FORCEPROP 1 LAST PIN_NAMES_ROTATE TRUE
J 2
(3625 1050);
DISPLAY 0.489362 (3625 1050);
PAINT GREEN (3625 1050);
DISPLAY INVISIBLE (3625 1050);
FORCEPROP 2 LAST CDS_LIB pure_quanta
J 2
(3625 1050);
DISPLAY INVISIBLE (3625 1050);
FORCEPROP 1 LAST CDS_LMAN_SYM_OUTLINE -25,50,25,-50
J 2
(3625 1050);
DISPLAY 0.468085 (3625 1050);
PAINT GREEN (3625 1050);
DISPLAY INVISIBLE (3625 1050);
FORCEPROP 2 LAST VOLTAGE 6.3V
J 2
(3275 1100);
DISPLAY 0.553191 (3275 1100);
DISPLAY INVISIBLE (3275 1100);
FORCEPROP 1 LAST MATERIAL X6S
J 2
(3634 1129);
DISPLAY 0.574468 (3634 1129);
PAINT GREEN (3634 1129);
DISPLAY INVISIBLE (3634 1129);
FORCEPROP 2 LAST PACK_TYPE C0201
J 2
(3450 1100);
DISPLAY 0.553191 (3450 1100);
DISPLAY INVISIBLE (3450 1100);
FORCEPROP 2 LAST TOLERANCE 20%
J 2
(3550 1100);
DISPLAY 0.553191 (3550 1100);
DISPLAY INVISIBLE (3550 1100);
FORCEPROP 1 LAST PATH I130
J 2
(3625 1050);
DISPLAY 0.723404 (3625 1050);
DISPLAY INVISIBLE (3625 1050);
FORCEPROP 1 LAST $LOCATION C764
J 0
(3875 1125);
DISPLAY 1.021277 (3875 1125);
DISPLAY INVISIBLE (3875 1125);
FORCEPROP 2 LAST CDS_LOCATION C764
J 0
(3875 1125);
DISPLAY 1.021277 (3875 1125);
DISPLAY INVISIBLE (3875 1125);
FORCEPROP 2 LAST $SEC 1
J 2
(3800 1125);
DISPLAY 0.680851 (3800 1125);
PAINT MONO (3800 1125);
DISPLAY INVISIBLE (3800 1125);
FORCEPROP 2 LAST CDS_SEC 1
J 2
(3800 1125);
DISPLAY 0.680851 (3800 1125);
DISPLAY INVISIBLE (3800 1125);
FORCEADD Q_CAP_DIFFBUS..2
R 2
(3625 1000);
FORCEPROP 1 LAST PART_NUMBER SP_CH4221MEE01
J 2
(3509 1088);
DISPLAY 0.574468 (3509 1088);
PAINT GREEN (3509 1088);
DISPLAY INVISIBLE (3509 1088);
FORCEPROP 2 LAST VALUE DIFF BUS_0.22UF
J 2
(3475 1000);
DISPLAY 0.553191 (3475 1000);
FORCEPROP 1 LAST $LOCATION C765
J 2
(3859 1017);
DISPLAY 0.723404 (3859 1017);
PAINT GREEN (3859 1017);
FORCEPROP 2 LASTPIN (3700 1000) $PN 1
J 0
(3710 1010);
DISPLAY 0.808511 (3710 1010);
FORCEPROP 2 LASTPIN (3550 1000) $PN 2
J 2
(3540 1010);
DISPLAY 0.808511 (3540 1010);
FORCEPROP 1 LAST PIN_NAMES_ROTATE TRUE
J 2
(3625 1000);
DISPLAY 0.489362 (3625 1000);
PAINT GREEN (3625 1000);
DISPLAY INVISIBLE (3625 1000);
FORCEPROP 2 LAST CDS_LIB pure_quanta
J 2
(3625 1000);
DISPLAY INVISIBLE (3625 1000);
FORCEPROP 1 LAST CDS_LMAN_SYM_OUTLINE -25,50,25,-50
J 2
(3625 1000);
DISPLAY 0.468085 (3625 1000);
PAINT GREEN (3625 1000);
DISPLAY INVISIBLE (3625 1000);
FORCEPROP 2 LAST VOLTAGE 6.3V
J 2
(3275 1050);
DISPLAY 0.553191 (3275 1050);
DISPLAY INVISIBLE (3275 1050);
FORCEPROP 1 LAST MATERIAL X6S
J 2
(3634 1079);
DISPLAY 0.574468 (3634 1079);
PAINT GREEN (3634 1079);
DISPLAY INVISIBLE (3634 1079);
FORCEPROP 2 LAST PACK_TYPE C0201
J 2
(3450 1050);
DISPLAY 0.553191 (3450 1050);
DISPLAY INVISIBLE (3450 1050);
FORCEPROP 2 LAST TOLERANCE 20%
J 2
(3550 1050);
DISPLAY 0.553191 (3550 1050);
DISPLAY INVISIBLE (3550 1050);
FORCEPROP 1 LAST PATH I131
J 2
(3625 1000);
DISPLAY 0.723404 (3625 1000);
DISPLAY INVISIBLE (3625 1000);
FORCEPROP 1 LAST $LOCATION C765
J 0
(3875 1075);
DISPLAY 1.021277 (3875 1075);
DISPLAY INVISIBLE (3875 1075);
FORCEPROP 2 LAST CDS_LOCATION C765
J 0
(3875 1075);
DISPLAY 1.021277 (3875 1075);
DISPLAY INVISIBLE (3875 1075);
FORCEPROP 2 LAST $SEC 1
J 2
(3800 1075);
DISPLAY 0.680851 (3800 1075);
PAINT MONO (3800 1075);
DISPLAY INVISIBLE (3800 1075);
FORCEPROP 2 LAST CDS_SEC 1
J 2
(3800 1075);
DISPLAY 0.680851 (3800 1075);
DISPLAY INVISIBLE (3800 1075);
FORCEADD TAP..1
R 2
(2900 1250);
FORCEPROP 3 LASTPIN (2950 1250) SIG_NAME P5E_CPU1_PE2_TX_DN<5>
J 0
(2960 1260);
DISPLAY 0.659574 (2960 1260);
PAINT MONO (2960 1260);
DISPLAY INVISIBLE (2960 1260);
FORCEPROP 1 LASTPIN (2950 1250) BN 5
J 2
(2962 1258);
DISPLAY 0.680851 (2962 1258);
PAINT GREEN (2962 1258);
FORCEPROP 2 LAST CDS_LIB standard
J 0
(2900 1250);
DISPLAY INVISIBLE (2900 1250);
FORCEPROP 1 LAST BODY_TYPE PLUMBING
J 2
(2900 1300);
DISPLAY 0.872340 (2900 1300);
PAINT GREEN (2900 1300);
DISPLAY INVISIBLE (2900 1300);
FORCEPROP 1 LAST HDL_TAP TRUE
J 2
(2575 1125);
DISPLAY 0.872340 (2575 1125);
DISPLAY INVISIBLE (2575 1125);
FORCEPROP 1 LAST PATH I132
J 2
(2902 1250);
DISPLAY 0.872340 (2902 1250);
PAINT GREEN (2902 1250);
DISPLAY INVISIBLE (2902 1250);
FORCEADD TAP..1
R 2
(2900 1450);
FORCEPROP 3 LASTPIN (2950 1450) SIG_NAME P5E_CPU1_PE2_TX_DN<6>
J 0
(2960 1460);
DISPLAY 0.659574 (2960 1460);
PAINT MONO (2960 1460);
DISPLAY INVISIBLE (2960 1460);
FORCEPROP 1 LASTPIN (2950 1450) BN 6
J 2
(2962 1458);
DISPLAY 0.680851 (2962 1458);
PAINT GREEN (2962 1458);
FORCEPROP 2 LAST CDS_LIB standard
J 0
(2900 1450);
DISPLAY INVISIBLE (2900 1450);
FORCEPROP 1 LAST BODY_TYPE PLUMBING
J 2
(2900 1500);
DISPLAY 0.872340 (2900 1500);
PAINT GREEN (2900 1500);
DISPLAY INVISIBLE (2900 1500);
FORCEPROP 1 LAST HDL_TAP TRUE
J 2
(2575 1325);
DISPLAY 0.872340 (2575 1325);
DISPLAY INVISIBLE (2575 1325);
FORCEPROP 1 LAST PATH I133
J 2
(2902 1450);
DISPLAY 0.872340 (2902 1450);
PAINT GREEN (2902 1450);
DISPLAY INVISIBLE (2902 1450);
FORCEADD TAP..1
R 2
(2900 1650);
FORCEPROP 3 LASTPIN (2950 1650) SIG_NAME P5E_CPU1_PE2_TX_DN<7>
J 0
(2960 1660);
DISPLAY 0.659574 (2960 1660);
PAINT MONO (2960 1660);
DISPLAY INVISIBLE (2960 1660);
FORCEPROP 1 LASTPIN (2950 1650) BN 7
J 2
(2962 1658);
DISPLAY 0.680851 (2962 1658);
PAINT GREEN (2962 1658);
FORCEPROP 2 LAST CDS_LIB standard
J 0
(2900 1650);
DISPLAY INVISIBLE (2900 1650);
FORCEPROP 1 LAST BODY_TYPE PLUMBING
J 2
(2900 1700);
DISPLAY 0.872340 (2900 1700);
PAINT GREEN (2900 1700);
DISPLAY INVISIBLE (2900 1700);
FORCEPROP 1 LAST HDL_TAP TRUE
J 2
(2575 1525);
DISPLAY 0.872340 (2575 1525);
DISPLAY INVISIBLE (2575 1525);
FORCEPROP 1 LAST PATH I134
J 2
(2902 1650);
DISPLAY 0.872340 (2902 1650);
PAINT GREEN (2902 1650);
DISPLAY INVISIBLE (2902 1650);
FORCEADD Q_CAP_DIFFBUS..2
R 2
(3625 1200);
FORCEPROP 1 LAST PART_NUMBER SP_CH4221MEE01
J 2
(3509 1288);
DISPLAY 0.574468 (3509 1288);
PAINT GREEN (3509 1288);
DISPLAY INVISIBLE (3509 1288);
FORCEPROP 2 LAST VALUE DIFF BUS_0.22UF
J 2
(3475 1200);
DISPLAY 0.553191 (3475 1200);
FORCEPROP 1 LAST $LOCATION C763
J 2
(3859 1217);
DISPLAY 0.723404 (3859 1217);
PAINT GREEN (3859 1217);
FORCEPROP 2 LASTPIN (3700 1200) $PN 1
J 0
(3710 1210);
DISPLAY 0.808511 (3710 1210);
FORCEPROP 2 LASTPIN (3550 1200) $PN 2
J 2
(3540 1210);
DISPLAY 0.808511 (3540 1210);
FORCEPROP 1 LAST PIN_NAMES_ROTATE TRUE
J 2
(3625 1200);
DISPLAY 0.489362 (3625 1200);
PAINT GREEN (3625 1200);
DISPLAY INVISIBLE (3625 1200);
FORCEPROP 2 LAST CDS_LIB pure_quanta
J 2
(3625 1200);
DISPLAY INVISIBLE (3625 1200);
FORCEPROP 1 LAST CDS_LMAN_SYM_OUTLINE -25,50,25,-50
J 2
(3625 1200);
DISPLAY 0.468085 (3625 1200);
PAINT GREEN (3625 1200);
DISPLAY INVISIBLE (3625 1200);
FORCEPROP 2 LAST VOLTAGE 6.3V
J 2
(3275 1250);
DISPLAY 0.553191 (3275 1250);
DISPLAY INVISIBLE (3275 1250);
FORCEPROP 1 LAST MATERIAL X6S
J 2
(3634 1279);
DISPLAY 0.574468 (3634 1279);
PAINT GREEN (3634 1279);
DISPLAY INVISIBLE (3634 1279);
FORCEPROP 2 LAST PACK_TYPE C0201
J 2
(3450 1250);
DISPLAY 0.553191 (3450 1250);
DISPLAY INVISIBLE (3450 1250);
FORCEPROP 2 LAST TOLERANCE 20%
J 2
(3550 1250);
DISPLAY 0.553191 (3550 1250);
DISPLAY INVISIBLE (3550 1250);
FORCEPROP 1 LAST PATH I135
J 2
(3625 1200);
DISPLAY 0.723404 (3625 1200);
DISPLAY INVISIBLE (3625 1200);
FORCEPROP 1 LAST $LOCATION C763
J 0
(3875 1275);
DISPLAY 1.021277 (3875 1275);
DISPLAY INVISIBLE (3875 1275);
FORCEPROP 2 LAST CDS_LOCATION C763
J 0
(3875 1275);
DISPLAY 1.021277 (3875 1275);
DISPLAY INVISIBLE (3875 1275);
FORCEPROP 2 LAST $SEC 1
J 2
(3800 1275);
DISPLAY 0.680851 (3800 1275);
PAINT MONO (3800 1275);
DISPLAY INVISIBLE (3800 1275);
FORCEPROP 2 LAST CDS_SEC 1
J 2
(3800 1275);
DISPLAY 0.680851 (3800 1275);
DISPLAY INVISIBLE (3800 1275);
FORCEADD Q_CAP_DIFFBUS..2
R 2
(3625 1250);
FORCEPROP 1 LAST PART_NUMBER SP_CH4221MEE01
J 2
(3509 1338);
DISPLAY 0.574468 (3509 1338);
PAINT GREEN (3509 1338);
DISPLAY INVISIBLE (3509 1338);
FORCEPROP 2 LAST VALUE DIFF BUS_0.22UF
J 2
(3475 1250);
DISPLAY 0.553191 (3475 1250);
FORCEPROP 1 LAST $LOCATION C762
J 2
(3859 1267);
DISPLAY 0.723404 (3859 1267);
PAINT GREEN (3859 1267);
FORCEPROP 2 LASTPIN (3700 1250) $PN 1
J 0
(3710 1260);
DISPLAY 0.808511 (3710 1260);
FORCEPROP 2 LASTPIN (3550 1250) $PN 2
J 2
(3540 1260);
DISPLAY 0.808511 (3540 1260);
FORCEPROP 1 LAST PIN_NAMES_ROTATE TRUE
J 2
(3625 1250);
DISPLAY 0.489362 (3625 1250);
PAINT GREEN (3625 1250);
DISPLAY INVISIBLE (3625 1250);
FORCEPROP 2 LAST CDS_LIB pure_quanta
J 2
(3625 1250);
DISPLAY INVISIBLE (3625 1250);
FORCEPROP 1 LAST CDS_LMAN_SYM_OUTLINE -25,50,25,-50
J 2
(3625 1250);
DISPLAY 0.468085 (3625 1250);
PAINT GREEN (3625 1250);
DISPLAY INVISIBLE (3625 1250);
FORCEPROP 2 LAST VOLTAGE 6.3V
J 2
(3275 1300);
DISPLAY 0.553191 (3275 1300);
DISPLAY INVISIBLE (3275 1300);
FORCEPROP 1 LAST MATERIAL X6S
J 2
(3634 1329);
DISPLAY 0.574468 (3634 1329);
PAINT GREEN (3634 1329);
DISPLAY INVISIBLE (3634 1329);
FORCEPROP 2 LAST PACK_TYPE C0201
J 2
(3450 1300);
DISPLAY 0.553191 (3450 1300);
DISPLAY INVISIBLE (3450 1300);
FORCEPROP 2 LAST TOLERANCE 20%
J 2
(3550 1300);
DISPLAY 0.553191 (3550 1300);
DISPLAY INVISIBLE (3550 1300);
FORCEPROP 1 LAST PATH I136
J 2
(3625 1250);
DISPLAY 0.723404 (3625 1250);
DISPLAY INVISIBLE (3625 1250);
FORCEPROP 1 LAST $LOCATION C762
J 0
(3875 1325);
DISPLAY 1.021277 (3875 1325);
DISPLAY INVISIBLE (3875 1325);
FORCEPROP 2 LAST CDS_LOCATION C762
J 0
(3875 1325);
DISPLAY 1.021277 (3875 1325);
DISPLAY INVISIBLE (3875 1325);
FORCEPROP 2 LAST $SEC 1
J 2
(3800 1325);
DISPLAY 0.680851 (3800 1325);
PAINT MONO (3800 1325);
DISPLAY INVISIBLE (3800 1325);
FORCEPROP 2 LAST CDS_SEC 1
J 2
(3800 1325);
DISPLAY 0.680851 (3800 1325);
DISPLAY INVISIBLE (3800 1325);
FORCEADD Q_CAP_DIFFBUS..2
R 2
(3625 1400);
FORCEPROP 1 LAST PART_NUMBER SP_CH4221MEE01
J 2
(3509 1488);
DISPLAY 0.574468 (3509 1488);
PAINT GREEN (3509 1488);
DISPLAY INVISIBLE (3509 1488);
FORCEPROP 2 LAST VALUE DIFF BUS_0.22UF
J 2
(3475 1400);
DISPLAY 0.553191 (3475 1400);
FORCEPROP 1 LAST $LOCATION C761
J 2
(3859 1417);
DISPLAY 0.723404 (3859 1417);
PAINT GREEN (3859 1417);
FORCEPROP 2 LASTPIN (3700 1400) $PN 1
J 0
(3710 1410);
DISPLAY 0.808511 (3710 1410);
FORCEPROP 2 LASTPIN (3550 1400) $PN 2
J 2
(3540 1410);
DISPLAY 0.808511 (3540 1410);
FORCEPROP 1 LAST PIN_NAMES_ROTATE TRUE
J 2
(3625 1400);
DISPLAY 0.489362 (3625 1400);
PAINT GREEN (3625 1400);
DISPLAY INVISIBLE (3625 1400);
FORCEPROP 2 LAST CDS_LIB pure_quanta
J 2
(3625 1400);
DISPLAY INVISIBLE (3625 1400);
FORCEPROP 1 LAST CDS_LMAN_SYM_OUTLINE -25,50,25,-50
J 2
(3625 1400);
DISPLAY 0.468085 (3625 1400);
PAINT GREEN (3625 1400);
DISPLAY INVISIBLE (3625 1400);
FORCEPROP 2 LAST VOLTAGE 6.3V
J 2
(3275 1450);
DISPLAY 0.553191 (3275 1450);
DISPLAY INVISIBLE (3275 1450);
FORCEPROP 1 LAST MATERIAL X6S
J 2
(3634 1479);
DISPLAY 0.574468 (3634 1479);
PAINT GREEN (3634 1479);
DISPLAY INVISIBLE (3634 1479);
FORCEPROP 2 LAST PACK_TYPE C0201
J 2
(3450 1450);
DISPLAY 0.553191 (3450 1450);
DISPLAY INVISIBLE (3450 1450);
FORCEPROP 2 LAST TOLERANCE 20%
J 2
(3550 1450);
DISPLAY 0.553191 (3550 1450);
DISPLAY INVISIBLE (3550 1450);
FORCEPROP 1 LAST PATH I137
J 2
(3625 1400);
DISPLAY 0.723404 (3625 1400);
DISPLAY INVISIBLE (3625 1400);
FORCEPROP 1 LAST $LOCATION C761
J 0
(3875 1475);
DISPLAY 1.021277 (3875 1475);
DISPLAY INVISIBLE (3875 1475);
FORCEPROP 2 LAST CDS_LOCATION C761
J 0
(3875 1475);
DISPLAY 1.021277 (3875 1475);
DISPLAY INVISIBLE (3875 1475);
FORCEPROP 2 LAST $SEC 1
J 2
(3800 1475);
DISPLAY 0.680851 (3800 1475);
PAINT MONO (3800 1475);
DISPLAY INVISIBLE (3800 1475);
FORCEPROP 2 LAST CDS_SEC 1
J 2
(3800 1475);
DISPLAY 0.680851 (3800 1475);
DISPLAY INVISIBLE (3800 1475);
FORCEADD Q_CAP_DIFFBUS..2
R 2
(3625 1450);
FORCEPROP 1 LAST PART_NUMBER SP_CH4221MEE01
J 2
(3509 1538);
DISPLAY 0.574468 (3509 1538);
PAINT GREEN (3509 1538);
DISPLAY INVISIBLE (3509 1538);
FORCEPROP 2 LAST VALUE DIFF BUS_0.22UF
J 2
(3475 1450);
DISPLAY 0.553191 (3475 1450);
FORCEPROP 1 LAST $LOCATION C760
J 2
(3859 1467);
DISPLAY 0.723404 (3859 1467);
PAINT GREEN (3859 1467);
FORCEPROP 2 LASTPIN (3700 1450) $PN 1
J 0
(3710 1460);
DISPLAY 0.808511 (3710 1460);
FORCEPROP 2 LASTPIN (3550 1450) $PN 2
J 2
(3540 1460);
DISPLAY 0.808511 (3540 1460);
FORCEPROP 1 LAST PIN_NAMES_ROTATE TRUE
J 2
(3625 1450);
DISPLAY 0.489362 (3625 1450);
PAINT GREEN (3625 1450);
DISPLAY INVISIBLE (3625 1450);
FORCEPROP 2 LAST CDS_LIB pure_quanta
J 2
(3625 1450);
DISPLAY INVISIBLE (3625 1450);
FORCEPROP 1 LAST CDS_LMAN_SYM_OUTLINE -25,50,25,-50
J 2
(3625 1450);
DISPLAY 0.468085 (3625 1450);
PAINT GREEN (3625 1450);
DISPLAY INVISIBLE (3625 1450);
FORCEPROP 2 LAST VOLTAGE 6.3V
J 2
(3275 1500);
DISPLAY 0.553191 (3275 1500);
DISPLAY INVISIBLE (3275 1500);
FORCEPROP 1 LAST MATERIAL X6S
J 2
(3634 1529);
DISPLAY 0.574468 (3634 1529);
PAINT GREEN (3634 1529);
DISPLAY INVISIBLE (3634 1529);
FORCEPROP 2 LAST PACK_TYPE C0201
J 2
(3450 1500);
DISPLAY 0.553191 (3450 1500);
DISPLAY INVISIBLE (3450 1500);
FORCEPROP 2 LAST TOLERANCE 20%
J 2
(3550 1500);
DISPLAY 0.553191 (3550 1500);
DISPLAY INVISIBLE (3550 1500);
FORCEPROP 1 LAST PATH I138
J 2
(3625 1450);
DISPLAY 0.723404 (3625 1450);
DISPLAY INVISIBLE (3625 1450);
FORCEPROP 1 LAST $LOCATION C760
J 0
(3875 1525);
DISPLAY 1.021277 (3875 1525);
DISPLAY INVISIBLE (3875 1525);
FORCEPROP 2 LAST CDS_LOCATION C760
J 0
(3875 1525);
DISPLAY 1.021277 (3875 1525);
DISPLAY INVISIBLE (3875 1525);
FORCEPROP 2 LAST $SEC 1
J 2
(3800 1525);
DISPLAY 0.680851 (3800 1525);
PAINT MONO (3800 1525);
DISPLAY INVISIBLE (3800 1525);
FORCEPROP 2 LAST CDS_SEC 1
J 2
(3800 1525);
DISPLAY 0.680851 (3800 1525);
DISPLAY INVISIBLE (3800 1525);
FORCEADD Q_CAP_DIFFBUS..2
R 2
(3625 1600);
FORCEPROP 1 LAST PART_NUMBER SP_CH4221MEE01
J 2
(3509 1688);
DISPLAY 0.574468 (3509 1688);
PAINT GREEN (3509 1688);
DISPLAY INVISIBLE (3509 1688);
FORCEPROP 2 LAST VALUE DIFF BUS_0.22UF
J 2
(3475 1600);
DISPLAY 0.553191 (3475 1600);
FORCEPROP 1 LAST $LOCATION C759
J 2
(3859 1617);
DISPLAY 0.723404 (3859 1617);
PAINT GREEN (3859 1617);
FORCEPROP 2 LASTPIN (3700 1600) $PN 1
J 0
(3710 1610);
DISPLAY 0.808511 (3710 1610);
FORCEPROP 2 LASTPIN (3550 1600) $PN 2
J 2
(3540 1610);
DISPLAY 0.808511 (3540 1610);
FORCEPROP 1 LAST PIN_NAMES_ROTATE TRUE
J 2
(3625 1600);
DISPLAY 0.489362 (3625 1600);
PAINT GREEN (3625 1600);
DISPLAY INVISIBLE (3625 1600);
FORCEPROP 2 LAST CDS_LIB pure_quanta
J 2
(3625 1600);
DISPLAY INVISIBLE (3625 1600);
FORCEPROP 1 LAST CDS_LMAN_SYM_OUTLINE -25,50,25,-50
J 2
(3625 1600);
DISPLAY 0.468085 (3625 1600);
PAINT GREEN (3625 1600);
DISPLAY INVISIBLE (3625 1600);
FORCEPROP 2 LAST VOLTAGE 6.3V
J 2
(3275 1650);
DISPLAY 0.553191 (3275 1650);
DISPLAY INVISIBLE (3275 1650);
FORCEPROP 1 LAST MATERIAL X6S
J 2
(3634 1679);
DISPLAY 0.574468 (3634 1679);
PAINT GREEN (3634 1679);
DISPLAY INVISIBLE (3634 1679);
FORCEPROP 2 LAST PACK_TYPE C0201
J 2
(3450 1650);
DISPLAY 0.553191 (3450 1650);
DISPLAY INVISIBLE (3450 1650);
FORCEPROP 2 LAST TOLERANCE 20%
J 2
(3550 1650);
DISPLAY 0.553191 (3550 1650);
DISPLAY INVISIBLE (3550 1650);
FORCEPROP 1 LAST PATH I139
J 2
(3625 1600);
DISPLAY 0.723404 (3625 1600);
DISPLAY INVISIBLE (3625 1600);
FORCEPROP 1 LAST $LOCATION C759
J 0
(3875 1675);
DISPLAY 1.021277 (3875 1675);
DISPLAY INVISIBLE (3875 1675);
FORCEPROP 2 LAST CDS_LOCATION C759
J 0
(3875 1675);
DISPLAY 1.021277 (3875 1675);
DISPLAY INVISIBLE (3875 1675);
FORCEPROP 2 LAST $SEC 1
J 2
(3800 1675);
DISPLAY 0.680851 (3800 1675);
PAINT MONO (3800 1675);
DISPLAY INVISIBLE (3800 1675);
FORCEPROP 2 LAST CDS_SEC 1
J 2
(3800 1675);
DISPLAY 0.680851 (3800 1675);
DISPLAY INVISIBLE (3800 1675);
FORCEADD Q_CAP_DIFFBUS..2
R 2
(3625 1650);
FORCEPROP 1 LAST PART_NUMBER SP_CH4221MEE01
J 2
(3509 1738);
DISPLAY 0.574468 (3509 1738);
PAINT GREEN (3509 1738);
DISPLAY INVISIBLE (3509 1738);
FORCEPROP 2 LAST VALUE DIFF BUS_0.22UF
J 2
(3475 1650);
DISPLAY 0.553191 (3475 1650);
FORCEPROP 1 LAST $LOCATION C758
J 2
(3859 1667);
DISPLAY 0.723404 (3859 1667);
PAINT GREEN (3859 1667);
FORCEPROP 2 LASTPIN (3700 1650) $PN 1
J 0
(3710 1660);
DISPLAY 0.808511 (3710 1660);
FORCEPROP 2 LASTPIN (3550 1650) $PN 2
J 2
(3540 1660);
DISPLAY 0.808511 (3540 1660);
FORCEPROP 1 LAST PIN_NAMES_ROTATE TRUE
J 2
(3625 1650);
DISPLAY 0.489362 (3625 1650);
PAINT GREEN (3625 1650);
DISPLAY INVISIBLE (3625 1650);
FORCEPROP 1 LAST CDS_LMAN_SYM_OUTLINE -25,50,25,-50
J 2
(3625 1650);
DISPLAY 0.468085 (3625 1650);
PAINT GREEN (3625 1650);
DISPLAY INVISIBLE (3625 1650);
FORCEPROP 2 LAST CDS_LIB pure_quanta
J 2
(3625 1650);
DISPLAY INVISIBLE (3625 1650);
FORCEPROP 2 LAST VOLTAGE 6.3V
J 2
(3275 1700);
DISPLAY 0.553191 (3275 1700);
DISPLAY INVISIBLE (3275 1700);
FORCEPROP 1 LAST MATERIAL X6S
J 2
(3634 1729);
DISPLAY 0.574468 (3634 1729);
PAINT GREEN (3634 1729);
DISPLAY INVISIBLE (3634 1729);
FORCEPROP 2 LAST PACK_TYPE C0201
J 2
(3450 1700);
DISPLAY 0.553191 (3450 1700);
DISPLAY INVISIBLE (3450 1700);
FORCEPROP 2 LAST TOLERANCE 20%
J 2
(3550 1700);
DISPLAY 0.553191 (3550 1700);
DISPLAY INVISIBLE (3550 1700);
FORCEPROP 1 LAST PATH I140
J 2
(3625 1650);
DISPLAY 0.723404 (3625 1650);
DISPLAY INVISIBLE (3625 1650);
FORCEPROP 1 LAST $LOCATION C758
J 0
(3875 1725);
DISPLAY 1.021277 (3875 1725);
DISPLAY INVISIBLE (3875 1725);
FORCEPROP 2 LAST CDS_LOCATION C758
J 0
(3875 1725);
DISPLAY 1.021277 (3875 1725);
DISPLAY INVISIBLE (3875 1725);
FORCEPROP 2 LAST $SEC 1
J 2
(3800 1725);
DISPLAY 0.680851 (3800 1725);
PAINT MONO (3800 1725);
DISPLAY INVISIBLE (3800 1725);
FORCEPROP 2 LAST CDS_SEC 1
J 2
(3800 1725);
DISPLAY 0.680851 (3800 1725);
DISPLAY INVISIBLE (3800 1725);
FORCEADD TAP..1
R 2
(2650 2175);
FORCEPROP 3 LASTPIN (2700 2175) SIG_NAME P5E_CPU1_PE2_TX_DP<8>
J 0
(2710 2185);
DISPLAY 0.659574 (2710 2185);
PAINT MONO (2710 2185);
DISPLAY INVISIBLE (2710 2185);
FORCEPROP 1 LASTPIN (2700 2175) BN 8
J 2
(2712 2183);
DISPLAY 0.680851 (2712 2183);
PAINT GREEN (2712 2183);
FORCEPROP 2 LAST CDS_LIB standard
J 0
(2650 2175);
DISPLAY INVISIBLE (2650 2175);
FORCEPROP 1 LAST BODY_TYPE PLUMBING
J 2
(2650 2225);
DISPLAY 0.872340 (2650 2225);
PAINT GREEN (2650 2225);
DISPLAY INVISIBLE (2650 2225);
FORCEPROP 1 LAST HDL_TAP TRUE
J 2
(2325 2050);
DISPLAY 0.872340 (2325 2050);
DISPLAY INVISIBLE (2325 2050);
FORCEPROP 1 LAST PATH I141
J 2
(2652 2175);
DISPLAY 0.872340 (2652 2175);
PAINT GREEN (2652 2175);
DISPLAY INVISIBLE (2652 2175);
FORCEADD TAP..1
R 2
(2650 2375);
FORCEPROP 3 LASTPIN (2700 2375) SIG_NAME P5E_CPU1_PE2_TX_DP<9>
J 0
(2710 2385);
DISPLAY 0.659574 (2710 2385);
PAINT MONO (2710 2385);
DISPLAY INVISIBLE (2710 2385);
FORCEPROP 1 LASTPIN (2700 2375) BN 9
J 2
(2712 2383);
DISPLAY 0.680851 (2712 2383);
PAINT GREEN (2712 2383);
FORCEPROP 2 LAST CDS_LIB standard
J 0
(2650 2375);
DISPLAY INVISIBLE (2650 2375);
FORCEPROP 1 LAST BODY_TYPE PLUMBING
J 2
(2650 2425);
DISPLAY 0.872340 (2650 2425);
PAINT GREEN (2650 2425);
DISPLAY INVISIBLE (2650 2425);
FORCEPROP 1 LAST HDL_TAP TRUE
J 2
(2325 2250);
DISPLAY 0.872340 (2325 2250);
DISPLAY INVISIBLE (2325 2250);
FORCEPROP 1 LAST PATH I142
J 2
(2652 2375);
DISPLAY 0.872340 (2652 2375);
PAINT GREEN (2652 2375);
DISPLAY INVISIBLE (2652 2375);
FORCEADD TAP..1
R 2
(2650 2575);
FORCEPROP 3 LASTPIN (2700 2575) SIG_NAME P5E_CPU1_PE2_TX_DP<10>
J 0
(2710 2585);
DISPLAY 0.659574 (2710 2585);
PAINT MONO (2710 2585);
DISPLAY INVISIBLE (2710 2585);
FORCEPROP 1 LASTPIN (2700 2575) BN 10
J 2
(2712 2583);
DISPLAY 0.680851 (2712 2583);
PAINT GREEN (2712 2583);
FORCEPROP 2 LAST CDS_LIB standard
J 0
(2650 2575);
DISPLAY INVISIBLE (2650 2575);
FORCEPROP 1 LAST BODY_TYPE PLUMBING
J 2
(2650 2625);
DISPLAY 0.872340 (2650 2625);
PAINT GREEN (2650 2625);
DISPLAY INVISIBLE (2650 2625);
FORCEPROP 1 LAST HDL_TAP TRUE
J 2
(2325 2450);
DISPLAY 0.872340 (2325 2450);
DISPLAY INVISIBLE (2325 2450);
FORCEPROP 1 LAST PATH I143
J 2
(2652 2575);
DISPLAY 0.872340 (2652 2575);
PAINT GREEN (2652 2575);
DISPLAY INVISIBLE (2652 2575);
FORCEADD TAP..1
R 2
(2650 2775);
FORCEPROP 3 LASTPIN (2700 2775) SIG_NAME P5E_CPU1_PE2_TX_DP<11>
J 0
(2710 2785);
DISPLAY 0.659574 (2710 2785);
PAINT MONO (2710 2785);
DISPLAY INVISIBLE (2710 2785);
FORCEPROP 1 LASTPIN (2700 2775) BN 11
J 2
(2712 2783);
DISPLAY 0.680851 (2712 2783);
PAINT GREEN (2712 2783);
FORCEPROP 2 LAST CDS_LIB standard
J 0
(2650 2775);
DISPLAY INVISIBLE (2650 2775);
FORCEPROP 1 LAST BODY_TYPE PLUMBING
J 2
(2650 2825);
DISPLAY 0.872340 (2650 2825);
PAINT GREEN (2650 2825);
DISPLAY INVISIBLE (2650 2825);
FORCEPROP 1 LAST HDL_TAP TRUE
J 2
(2325 2650);
DISPLAY 0.872340 (2325 2650);
DISPLAY INVISIBLE (2325 2650);
FORCEPROP 1 LAST PATH I144
J 2
(2652 2775);
DISPLAY 0.872340 (2652 2775);
PAINT GREEN (2652 2775);
DISPLAY INVISIBLE (2652 2775);
FORCEADD TAP..1
R 2
(2650 2975);
FORCEPROP 3 LASTPIN (2700 2975) SIG_NAME P5E_CPU1_PE2_TX_DP<12>
J 0
(2710 2985);
DISPLAY 0.659574 (2710 2985);
PAINT MONO (2710 2985);
DISPLAY INVISIBLE (2710 2985);
FORCEPROP 1 LASTPIN (2700 2975) BN 12
J 2
(2712 2983);
DISPLAY 0.680851 (2712 2983);
PAINT GREEN (2712 2983);
FORCEPROP 2 LAST CDS_LIB standard
J 0
(2650 2975);
DISPLAY INVISIBLE (2650 2975);
FORCEPROP 1 LAST BODY_TYPE PLUMBING
J 2
(2650 3025);
DISPLAY 0.872340 (2650 3025);
PAINT GREEN (2650 3025);
DISPLAY INVISIBLE (2650 3025);
FORCEPROP 1 LAST HDL_TAP TRUE
J 2
(2325 2850);
DISPLAY 0.872340 (2325 2850);
DISPLAY INVISIBLE (2325 2850);
FORCEPROP 1 LAST PATH I145
J 2
(2652 2975);
DISPLAY 0.872340 (2652 2975);
PAINT GREEN (2652 2975);
DISPLAY INVISIBLE (2652 2975);
FORCEADD TAP..1
R 2
(2650 3175);
FORCEPROP 3 LASTPIN (2700 3175) SIG_NAME P5E_CPU1_PE2_TX_DP<13>
J 0
(2710 3185);
DISPLAY 0.659574 (2710 3185);
PAINT MONO (2710 3185);
DISPLAY INVISIBLE (2710 3185);
FORCEPROP 1 LASTPIN (2700 3175) BN 13
J 2
(2712 3183);
DISPLAY 0.680851 (2712 3183);
PAINT GREEN (2712 3183);
FORCEPROP 2 LAST CDS_LIB standard
J 0
(2650 3175);
DISPLAY INVISIBLE (2650 3175);
FORCEPROP 1 LAST BODY_TYPE PLUMBING
J 2
(2650 3225);
DISPLAY 0.872340 (2650 3225);
PAINT GREEN (2650 3225);
DISPLAY INVISIBLE (2650 3225);
FORCEPROP 1 LAST HDL_TAP TRUE
J 2
(2325 3050);
DISPLAY 0.872340 (2325 3050);
DISPLAY INVISIBLE (2325 3050);
FORCEPROP 1 LAST PATH I146
J 2
(2652 3175);
DISPLAY 0.872340 (2652 3175);
PAINT GREEN (2652 3175);
DISPLAY INVISIBLE (2652 3175);
FORCEADD TAP..1
R 2
(2650 3375);
FORCEPROP 3 LASTPIN (2700 3375) SIG_NAME P5E_CPU1_PE2_TX_DP<14>
J 0
(2710 3385);
DISPLAY 0.659574 (2710 3385);
PAINT MONO (2710 3385);
DISPLAY INVISIBLE (2710 3385);
FORCEPROP 1 LASTPIN (2700 3375) BN 14
J 2
(2712 3383);
DISPLAY 0.680851 (2712 3383);
PAINT GREEN (2712 3383);
FORCEPROP 2 LAST CDS_LIB standard
J 0
(2650 3375);
DISPLAY INVISIBLE (2650 3375);
FORCEPROP 1 LAST BODY_TYPE PLUMBING
J 2
(2650 3425);
DISPLAY 0.872340 (2650 3425);
PAINT GREEN (2650 3425);
DISPLAY INVISIBLE (2650 3425);
FORCEPROP 1 LAST HDL_TAP TRUE
J 2
(2325 3250);
DISPLAY 0.872340 (2325 3250);
DISPLAY INVISIBLE (2325 3250);
FORCEPROP 1 LAST PATH I147
J 2
(2652 3375);
DISPLAY 0.872340 (2652 3375);
PAINT GREEN (2652 3375);
DISPLAY INVISIBLE (2652 3375);
FORCEADD TAP..1
R 2
(2650 3575);
FORCEPROP 3 LASTPIN (2700 3575) SIG_NAME P5E_CPU1_PE2_TX_DP<15>
J 0
(2710 3585);
DISPLAY 0.659574 (2710 3585);
PAINT MONO (2710 3585);
DISPLAY INVISIBLE (2710 3585);
FORCEPROP 1 LASTPIN (2700 3575) BN 15
J 2
(2712 3583);
DISPLAY 0.680851 (2712 3583);
PAINT GREEN (2712 3583);
FORCEPROP 2 LAST CDS_LIB standard
J 0
(2650 3575);
DISPLAY INVISIBLE (2650 3575);
FORCEPROP 1 LAST BODY_TYPE PLUMBING
J 2
(2650 3625);
DISPLAY 0.872340 (2650 3625);
PAINT GREEN (2650 3625);
DISPLAY INVISIBLE (2650 3625);
FORCEPROP 1 LAST HDL_TAP TRUE
J 2
(2325 3450);
DISPLAY 0.872340 (2325 3450);
DISPLAY INVISIBLE (2325 3450);
FORCEPROP 1 LAST PATH I148
J 2
(2652 3575);
DISPLAY 0.872340 (2652 3575);
PAINT GREEN (2652 3575);
DISPLAY INVISIBLE (2652 3575);
FORCEADD TAP..1
R 2
(2900 2225);
FORCEPROP 3 LASTPIN (2950 2225) SIG_NAME P5E_CPU1_PE2_TX_DN<8>
J 0
(2960 2235);
DISPLAY 0.659574 (2960 2235);
PAINT MONO (2960 2235);
DISPLAY INVISIBLE (2960 2235);
FORCEPROP 1 LASTPIN (2950 2225) BN 8
J 2
(2962 2233);
DISPLAY 0.680851 (2962 2233);
PAINT GREEN (2962 2233);
FORCEPROP 2 LAST CDS_LIB standard
J 0
(2900 2225);
DISPLAY INVISIBLE (2900 2225);
FORCEPROP 1 LAST BODY_TYPE PLUMBING
J 2
(2900 2275);
DISPLAY 0.872340 (2900 2275);
PAINT GREEN (2900 2275);
DISPLAY INVISIBLE (2900 2275);
FORCEPROP 1 LAST HDL_TAP TRUE
J 2
(2575 2100);
DISPLAY 0.872340 (2575 2100);
DISPLAY INVISIBLE (2575 2100);
FORCEPROP 1 LAST PATH I149
J 2
(2902 2225);
DISPLAY 0.872340 (2902 2225);
PAINT GREEN (2902 2225);
DISPLAY INVISIBLE (2902 2225);
FORCEADD TAP..1
R 2
(2900 2425);
FORCEPROP 3 LASTPIN (2950 2425) SIG_NAME P5E_CPU1_PE2_TX_DN<9>
J 0
(2960 2435);
DISPLAY 0.659574 (2960 2435);
PAINT MONO (2960 2435);
DISPLAY INVISIBLE (2960 2435);
FORCEPROP 1 LASTPIN (2950 2425) BN 9
J 2
(2962 2433);
DISPLAY 0.680851 (2962 2433);
PAINT GREEN (2962 2433);
FORCEPROP 2 LAST CDS_LIB standard
J 0
(2900 2425);
DISPLAY INVISIBLE (2900 2425);
FORCEPROP 1 LAST BODY_TYPE PLUMBING
J 2
(2900 2475);
DISPLAY 0.872340 (2900 2475);
PAINT GREEN (2900 2475);
DISPLAY INVISIBLE (2900 2475);
FORCEPROP 1 LAST HDL_TAP TRUE
J 2
(2575 2300);
DISPLAY 0.872340 (2575 2300);
DISPLAY INVISIBLE (2575 2300);
FORCEPROP 1 LAST PATH I150
J 2
(2902 2425);
DISPLAY 0.872340 (2902 2425);
PAINT GREEN (2902 2425);
DISPLAY INVISIBLE (2902 2425);
FORCEADD TAP..1
R 2
(2900 2625);
FORCEPROP 3 LASTPIN (2950 2625) SIG_NAME P5E_CPU1_PE2_TX_DN<10>
J 0
(2960 2635);
DISPLAY 0.659574 (2960 2635);
PAINT MONO (2960 2635);
DISPLAY INVISIBLE (2960 2635);
FORCEPROP 1 LASTPIN (2950 2625) BN 10
J 2
(2962 2633);
DISPLAY 0.680851 (2962 2633);
PAINT GREEN (2962 2633);
FORCEPROP 2 LAST CDS_LIB standard
J 0
(2900 2625);
DISPLAY INVISIBLE (2900 2625);
FORCEPROP 1 LAST BODY_TYPE PLUMBING
J 2
(2900 2675);
DISPLAY 0.872340 (2900 2675);
PAINT GREEN (2900 2675);
DISPLAY INVISIBLE (2900 2675);
FORCEPROP 1 LAST HDL_TAP TRUE
J 2
(2575 2500);
DISPLAY 0.872340 (2575 2500);
DISPLAY INVISIBLE (2575 2500);
FORCEPROP 1 LAST PATH I151
J 2
(2902 2625);
DISPLAY 0.872340 (2902 2625);
PAINT GREEN (2902 2625);
DISPLAY INVISIBLE (2902 2625);
FORCEADD TAP..1
R 2
(2900 2825);
FORCEPROP 3 LASTPIN (2950 2825) SIG_NAME P5E_CPU1_PE2_TX_DN<11>
J 0
(2960 2835);
DISPLAY 0.659574 (2960 2835);
PAINT MONO (2960 2835);
DISPLAY INVISIBLE (2960 2835);
FORCEPROP 1 LASTPIN (2950 2825) BN 11
J 2
(2962 2833);
DISPLAY 0.680851 (2962 2833);
PAINT GREEN (2962 2833);
FORCEPROP 2 LAST CDS_LIB standard
J 0
(2900 2825);
DISPLAY INVISIBLE (2900 2825);
FORCEPROP 1 LAST BODY_TYPE PLUMBING
J 2
(2900 2875);
DISPLAY 0.872340 (2900 2875);
PAINT GREEN (2900 2875);
DISPLAY INVISIBLE (2900 2875);
FORCEPROP 1 LAST HDL_TAP TRUE
J 2
(2575 2700);
DISPLAY 0.872340 (2575 2700);
DISPLAY INVISIBLE (2575 2700);
FORCEPROP 1 LAST PATH I152
J 2
(2902 2825);
DISPLAY 0.872340 (2902 2825);
PAINT GREEN (2902 2825);
DISPLAY INVISIBLE (2902 2825);
FORCEADD TAP..1
R 2
(2900 3025);
FORCEPROP 3 LASTPIN (2950 3025) SIG_NAME P5E_CPU1_PE2_TX_DN<12>
J 0
(2960 3035);
DISPLAY 0.659574 (2960 3035);
PAINT MONO (2960 3035);
DISPLAY INVISIBLE (2960 3035);
FORCEPROP 1 LASTPIN (2950 3025) BN 12
J 2
(2962 3033);
DISPLAY 0.680851 (2962 3033);
PAINT GREEN (2962 3033);
FORCEPROP 2 LAST CDS_LIB standard
J 0
(2900 3025);
DISPLAY INVISIBLE (2900 3025);
FORCEPROP 1 LAST BODY_TYPE PLUMBING
J 2
(2900 3075);
DISPLAY 0.872340 (2900 3075);
PAINT GREEN (2900 3075);
DISPLAY INVISIBLE (2900 3075);
FORCEPROP 1 LAST HDL_TAP TRUE
J 2
(2575 2900);
DISPLAY 0.872340 (2575 2900);
DISPLAY INVISIBLE (2575 2900);
FORCEPROP 1 LAST PATH I153
J 2
(2902 3025);
DISPLAY 0.872340 (2902 3025);
PAINT GREEN (2902 3025);
DISPLAY INVISIBLE (2902 3025);
FORCEADD Q_CAP_DIFFBUS..2
R 2
(3625 2225);
FORCEPROP 1 LAST PART_NUMBER SP_CH4221MEE01
J 2
(3509 2313);
DISPLAY 0.574468 (3509 2313);
PAINT GREEN (3509 2313);
DISPLAY INVISIBLE (3509 2313);
FORCEPROP 2 LAST VALUE DIFF BUS_0.22UF
J 2
(3475 2225);
DISPLAY 0.553191 (3475 2225);
FORCEPROP 1 LAST $LOCATION C756
J 2
(3859 2242);
DISPLAY 0.723404 (3859 2242);
PAINT GREEN (3859 2242);
FORCEPROP 2 LASTPIN (3700 2225) $PN 1
J 0
(3710 2235);
DISPLAY 0.808511 (3710 2235);
FORCEPROP 2 LASTPIN (3550 2225) $PN 2
J 2
(3540 2235);
DISPLAY 0.808511 (3540 2235);
FORCEPROP 1 LAST CDS_LMAN_SYM_OUTLINE -25,50,25,-50
J 2
(3625 2225);
DISPLAY 0.468085 (3625 2225);
PAINT GREEN (3625 2225);
DISPLAY INVISIBLE (3625 2225);
FORCEPROP 2 LAST CDS_LIB pure_quanta
J 2
(3625 2225);
DISPLAY INVISIBLE (3625 2225);
FORCEPROP 1 LAST PIN_NAMES_ROTATE TRUE
J 2
(3625 2225);
DISPLAY 0.489362 (3625 2225);
PAINT GREEN (3625 2225);
DISPLAY INVISIBLE (3625 2225);
FORCEPROP 2 LAST VOLTAGE 6.3V
J 2
(3275 2275);
DISPLAY 0.553191 (3275 2275);
DISPLAY INVISIBLE (3275 2275);
FORCEPROP 1 LAST MATERIAL X6S
J 2
(3634 2304);
DISPLAY 0.574468 (3634 2304);
PAINT GREEN (3634 2304);
DISPLAY INVISIBLE (3634 2304);
FORCEPROP 2 LAST PACK_TYPE C0201
J 2
(3450 2275);
DISPLAY 0.553191 (3450 2275);
DISPLAY INVISIBLE (3450 2275);
FORCEPROP 2 LAST TOLERANCE 20%
J 2
(3550 2275);
DISPLAY 0.553191 (3550 2275);
DISPLAY INVISIBLE (3550 2275);
FORCEPROP 1 LAST PATH I154
J 2
(3625 2225);
DISPLAY 0.723404 (3625 2225);
DISPLAY INVISIBLE (3625 2225);
FORCEPROP 1 LAST $LOCATION C756
J 0
(3875 2300);
DISPLAY 1.021277 (3875 2300);
DISPLAY INVISIBLE (3875 2300);
FORCEPROP 2 LAST CDS_LOCATION C756
J 0
(3875 2300);
DISPLAY 1.021277 (3875 2300);
DISPLAY INVISIBLE (3875 2300);
FORCEPROP 2 LAST $SEC 1
J 2
(3800 2300);
DISPLAY 0.680851 (3800 2300);
PAINT MONO (3800 2300);
DISPLAY INVISIBLE (3800 2300);
FORCEPROP 2 LAST CDS_SEC 1
J 2
(3800 2300);
DISPLAY 0.680851 (3800 2300);
DISPLAY INVISIBLE (3800 2300);
FORCEADD Q_CAP_DIFFBUS..2
R 2
(3625 2175);
FORCEPROP 1 LAST PART_NUMBER SP_CH4221MEE01
J 2
(3509 2263);
DISPLAY 0.574468 (3509 2263);
PAINT GREEN (3509 2263);
DISPLAY INVISIBLE (3509 2263);
FORCEPROP 2 LAST VALUE DIFF BUS_0.22UF
J 2
(3475 2175);
DISPLAY 0.553191 (3475 2175);
FORCEPROP 1 LAST $LOCATION C757
J 2
(3859 2192);
DISPLAY 0.723404 (3859 2192);
PAINT GREEN (3859 2192);
FORCEPROP 2 LASTPIN (3700 2175) $PN 1
J 0
(3710 2185);
DISPLAY 0.808511 (3710 2185);
FORCEPROP 2 LASTPIN (3550 2175) $PN 2
J 2
(3540 2185);
DISPLAY 0.808511 (3540 2185);
FORCEPROP 1 LAST CDS_LMAN_SYM_OUTLINE -25,50,25,-50
J 2
(3625 2175);
DISPLAY 0.468085 (3625 2175);
PAINT GREEN (3625 2175);
DISPLAY INVISIBLE (3625 2175);
FORCEPROP 2 LAST CDS_LIB pure_quanta
J 2
(3625 2175);
DISPLAY INVISIBLE (3625 2175);
FORCEPROP 1 LAST PIN_NAMES_ROTATE TRUE
J 2
(3625 2175);
DISPLAY 0.489362 (3625 2175);
PAINT GREEN (3625 2175);
DISPLAY INVISIBLE (3625 2175);
FORCEPROP 2 LAST VOLTAGE 6.3V
J 2
(3275 2225);
DISPLAY 0.553191 (3275 2225);
DISPLAY INVISIBLE (3275 2225);
FORCEPROP 1 LAST MATERIAL X6S
J 2
(3634 2254);
DISPLAY 0.574468 (3634 2254);
PAINT GREEN (3634 2254);
DISPLAY INVISIBLE (3634 2254);
FORCEPROP 2 LAST PACK_TYPE C0201
J 2
(3450 2225);
DISPLAY 0.553191 (3450 2225);
DISPLAY INVISIBLE (3450 2225);
FORCEPROP 2 LAST TOLERANCE 20%
J 2
(3550 2225);
DISPLAY 0.553191 (3550 2225);
DISPLAY INVISIBLE (3550 2225);
FORCEPROP 1 LAST PATH I155
J 2
(3625 2175);
DISPLAY 0.723404 (3625 2175);
DISPLAY INVISIBLE (3625 2175);
FORCEPROP 1 LAST $LOCATION C757
J 0
(3875 2250);
DISPLAY 1.021277 (3875 2250);
DISPLAY INVISIBLE (3875 2250);
FORCEPROP 2 LAST CDS_LOCATION C757
J 0
(3875 2250);
DISPLAY 1.021277 (3875 2250);
DISPLAY INVISIBLE (3875 2250);
FORCEPROP 2 LAST $SEC 1
J 2
(3800 2250);
DISPLAY 0.680851 (3800 2250);
PAINT MONO (3800 2250);
DISPLAY INVISIBLE (3800 2250);
FORCEPROP 2 LAST CDS_SEC 1
J 2
(3800 2250);
DISPLAY 0.680851 (3800 2250);
DISPLAY INVISIBLE (3800 2250);
FORCEADD Q_CAP_DIFFBUS..2
R 2
(3625 2375);
FORCEPROP 1 LAST PART_NUMBER SP_CH4221MEE01
J 2
(3509 2463);
DISPLAY 0.574468 (3509 2463);
PAINT GREEN (3509 2463);
DISPLAY INVISIBLE (3509 2463);
FORCEPROP 2 LAST VALUE DIFF BUS_0.22UF
J 2
(3475 2375);
DISPLAY 0.553191 (3475 2375);
FORCEPROP 1 LAST $LOCATION C755
J 2
(3859 2392);
DISPLAY 0.723404 (3859 2392);
PAINT GREEN (3859 2392);
FORCEPROP 2 LASTPIN (3700 2375) $PN 1
J 0
(3710 2385);
DISPLAY 0.808511 (3710 2385);
FORCEPROP 2 LASTPIN (3550 2375) $PN 2
J 2
(3540 2385);
DISPLAY 0.808511 (3540 2385);
FORCEPROP 1 LAST CDS_LMAN_SYM_OUTLINE -25,50,25,-50
J 2
(3625 2375);
DISPLAY 0.468085 (3625 2375);
PAINT GREEN (3625 2375);
DISPLAY INVISIBLE (3625 2375);
FORCEPROP 2 LAST CDS_LIB pure_quanta
J 2
(3625 2375);
DISPLAY INVISIBLE (3625 2375);
FORCEPROP 1 LAST PIN_NAMES_ROTATE TRUE
J 2
(3625 2375);
DISPLAY 0.489362 (3625 2375);
PAINT GREEN (3625 2375);
DISPLAY INVISIBLE (3625 2375);
FORCEPROP 2 LAST VOLTAGE 6.3V
J 2
(3275 2425);
DISPLAY 0.553191 (3275 2425);
DISPLAY INVISIBLE (3275 2425);
FORCEPROP 1 LAST MATERIAL X6S
J 2
(3634 2454);
DISPLAY 0.574468 (3634 2454);
PAINT GREEN (3634 2454);
DISPLAY INVISIBLE (3634 2454);
FORCEPROP 2 LAST PACK_TYPE C0201
J 2
(3450 2425);
DISPLAY 0.553191 (3450 2425);
DISPLAY INVISIBLE (3450 2425);
FORCEPROP 2 LAST TOLERANCE 20%
J 2
(3550 2425);
DISPLAY 0.553191 (3550 2425);
DISPLAY INVISIBLE (3550 2425);
FORCEPROP 1 LAST PATH I156
J 2
(3625 2375);
DISPLAY 0.723404 (3625 2375);
DISPLAY INVISIBLE (3625 2375);
FORCEPROP 1 LAST $LOCATION C755
J 0
(3875 2450);
DISPLAY 1.021277 (3875 2450);
DISPLAY INVISIBLE (3875 2450);
FORCEPROP 2 LAST CDS_LOCATION C755
J 0
(3875 2450);
DISPLAY 1.021277 (3875 2450);
DISPLAY INVISIBLE (3875 2450);
FORCEPROP 2 LAST $SEC 1
J 2
(3800 2450);
DISPLAY 0.680851 (3800 2450);
PAINT MONO (3800 2450);
DISPLAY INVISIBLE (3800 2450);
FORCEPROP 2 LAST CDS_SEC 1
J 2
(3800 2450);
DISPLAY 0.680851 (3800 2450);
DISPLAY INVISIBLE (3800 2450);
FORCEADD Q_CAP_DIFFBUS..2
R 2
(3625 2425);
FORCEPROP 1 LAST PART_NUMBER SP_CH4221MEE01
J 2
(3509 2513);
DISPLAY 0.574468 (3509 2513);
PAINT GREEN (3509 2513);
DISPLAY INVISIBLE (3509 2513);
FORCEPROP 2 LAST VALUE DIFF BUS_0.22UF
J 2
(3475 2425);
DISPLAY 0.553191 (3475 2425);
FORCEPROP 1 LAST $LOCATION C754
J 2
(3859 2442);
DISPLAY 0.723404 (3859 2442);
PAINT GREEN (3859 2442);
FORCEPROP 2 LASTPIN (3700 2425) $PN 1
J 0
(3710 2435);
DISPLAY 0.808511 (3710 2435);
FORCEPROP 2 LASTPIN (3550 2425) $PN 2
J 2
(3540 2435);
DISPLAY 0.808511 (3540 2435);
FORCEPROP 2 LAST CDS_LIB pure_quanta
J 2
(3625 2425);
DISPLAY INVISIBLE (3625 2425);
FORCEPROP 1 LAST CDS_LMAN_SYM_OUTLINE -25,50,25,-50
J 2
(3625 2425);
DISPLAY 0.468085 (3625 2425);
PAINT GREEN (3625 2425);
DISPLAY INVISIBLE (3625 2425);
FORCEPROP 1 LAST PIN_NAMES_ROTATE TRUE
J 2
(3625 2425);
DISPLAY 0.489362 (3625 2425);
PAINT GREEN (3625 2425);
DISPLAY INVISIBLE (3625 2425);
FORCEPROP 2 LAST VOLTAGE 6.3V
J 2
(3275 2475);
DISPLAY 0.553191 (3275 2475);
DISPLAY INVISIBLE (3275 2475);
FORCEPROP 1 LAST MATERIAL X6S
J 2
(3634 2504);
DISPLAY 0.574468 (3634 2504);
PAINT GREEN (3634 2504);
DISPLAY INVISIBLE (3634 2504);
FORCEPROP 2 LAST PACK_TYPE C0201
J 2
(3450 2475);
DISPLAY 0.553191 (3450 2475);
DISPLAY INVISIBLE (3450 2475);
FORCEPROP 2 LAST TOLERANCE 20%
J 2
(3550 2475);
DISPLAY 0.553191 (3550 2475);
DISPLAY INVISIBLE (3550 2475);
FORCEPROP 1 LAST PATH I157
J 2
(3625 2425);
DISPLAY 0.723404 (3625 2425);
DISPLAY INVISIBLE (3625 2425);
FORCEPROP 1 LAST $LOCATION C754
J 0
(3875 2500);
DISPLAY 1.021277 (3875 2500);
DISPLAY INVISIBLE (3875 2500);
FORCEPROP 2 LAST CDS_LOCATION C754
J 0
(3875 2500);
DISPLAY 1.021277 (3875 2500);
DISPLAY INVISIBLE (3875 2500);
FORCEPROP 2 LAST $SEC 1
J 2
(3800 2500);
DISPLAY 0.680851 (3800 2500);
PAINT MONO (3800 2500);
DISPLAY INVISIBLE (3800 2500);
FORCEPROP 2 LAST CDS_SEC 1
J 2
(3800 2500);
DISPLAY 0.680851 (3800 2500);
DISPLAY INVISIBLE (3800 2500);
FORCEADD Q_CAP_DIFFBUS..2
R 2
(3625 2575);
FORCEPROP 1 LAST PART_NUMBER SP_CH4221MEE01
J 2
(3509 2663);
DISPLAY 0.574468 (3509 2663);
PAINT GREEN (3509 2663);
DISPLAY INVISIBLE (3509 2663);
FORCEPROP 2 LAST VALUE DIFF BUS_0.22UF
J 2
(3475 2575);
DISPLAY 0.553191 (3475 2575);
FORCEPROP 1 LAST $LOCATION C753
J 2
(3859 2592);
DISPLAY 0.723404 (3859 2592);
PAINT GREEN (3859 2592);
FORCEPROP 2 LASTPIN (3700 2575) $PN 1
J 0
(3710 2585);
DISPLAY 0.808511 (3710 2585);
FORCEPROP 2 LASTPIN (3550 2575) $PN 2
J 2
(3540 2585);
DISPLAY 0.808511 (3540 2585);
FORCEPROP 1 LAST CDS_LMAN_SYM_OUTLINE -25,50,25,-50
J 2
(3625 2575);
DISPLAY 0.468085 (3625 2575);
PAINT GREEN (3625 2575);
DISPLAY INVISIBLE (3625 2575);
FORCEPROP 2 LAST CDS_LIB pure_quanta
J 2
(3625 2575);
DISPLAY INVISIBLE (3625 2575);
FORCEPROP 1 LAST PIN_NAMES_ROTATE TRUE
J 2
(3625 2575);
DISPLAY 0.489362 (3625 2575);
PAINT GREEN (3625 2575);
DISPLAY INVISIBLE (3625 2575);
FORCEPROP 2 LAST VOLTAGE 6.3V
J 2
(3275 2625);
DISPLAY 0.553191 (3275 2625);
DISPLAY INVISIBLE (3275 2625);
FORCEPROP 1 LAST MATERIAL X6S
J 2
(3634 2654);
DISPLAY 0.574468 (3634 2654);
PAINT GREEN (3634 2654);
DISPLAY INVISIBLE (3634 2654);
FORCEPROP 2 LAST PACK_TYPE C0201
J 2
(3450 2625);
DISPLAY 0.553191 (3450 2625);
DISPLAY INVISIBLE (3450 2625);
FORCEPROP 2 LAST TOLERANCE 20%
J 2
(3550 2625);
DISPLAY 0.553191 (3550 2625);
DISPLAY INVISIBLE (3550 2625);
FORCEPROP 1 LAST PATH I158
J 2
(3625 2575);
DISPLAY 0.723404 (3625 2575);
DISPLAY INVISIBLE (3625 2575);
FORCEPROP 1 LAST $LOCATION C753
J 0
(3875 2650);
DISPLAY 1.021277 (3875 2650);
DISPLAY INVISIBLE (3875 2650);
FORCEPROP 2 LAST CDS_LOCATION C753
J 0
(3875 2650);
DISPLAY 1.021277 (3875 2650);
DISPLAY INVISIBLE (3875 2650);
FORCEPROP 2 LAST $SEC 1
J 2
(3800 2650);
DISPLAY 0.680851 (3800 2650);
PAINT MONO (3800 2650);
DISPLAY INVISIBLE (3800 2650);
FORCEPROP 2 LAST CDS_SEC 1
J 2
(3800 2650);
DISPLAY 0.680851 (3800 2650);
DISPLAY INVISIBLE (3800 2650);
FORCEADD Q_CAP_DIFFBUS..2
R 2
(3625 2625);
FORCEPROP 1 LAST PART_NUMBER SP_CH4221MEE01
J 2
(3509 2713);
DISPLAY 0.574468 (3509 2713);
PAINT GREEN (3509 2713);
DISPLAY INVISIBLE (3509 2713);
FORCEPROP 2 LAST VALUE DIFF BUS_0.22UF
J 2
(3475 2625);
DISPLAY 0.553191 (3475 2625);
FORCEPROP 1 LAST $LOCATION C752
J 2
(3859 2642);
DISPLAY 0.723404 (3859 2642);
PAINT GREEN (3859 2642);
FORCEPROP 2 LASTPIN (3700 2625) $PN 1
J 0
(3710 2635);
DISPLAY 0.808511 (3710 2635);
FORCEPROP 2 LASTPIN (3550 2625) $PN 2
J 2
(3540 2635);
DISPLAY 0.808511 (3540 2635);
FORCEPROP 1 LAST CDS_LMAN_SYM_OUTLINE -25,50,25,-50
J 2
(3625 2625);
DISPLAY 0.468085 (3625 2625);
PAINT GREEN (3625 2625);
DISPLAY INVISIBLE (3625 2625);
FORCEPROP 2 LAST CDS_LIB pure_quanta
J 2
(3625 2625);
DISPLAY INVISIBLE (3625 2625);
FORCEPROP 1 LAST PIN_NAMES_ROTATE TRUE
J 2
(3625 2625);
DISPLAY 0.489362 (3625 2625);
PAINT GREEN (3625 2625);
DISPLAY INVISIBLE (3625 2625);
FORCEPROP 2 LAST VOLTAGE 6.3V
J 2
(3275 2675);
DISPLAY 0.553191 (3275 2675);
DISPLAY INVISIBLE (3275 2675);
FORCEPROP 1 LAST MATERIAL X6S
J 2
(3634 2704);
DISPLAY 0.574468 (3634 2704);
PAINT GREEN (3634 2704);
DISPLAY INVISIBLE (3634 2704);
FORCEPROP 2 LAST PACK_TYPE C0201
J 2
(3450 2675);
DISPLAY 0.553191 (3450 2675);
DISPLAY INVISIBLE (3450 2675);
FORCEPROP 2 LAST TOLERANCE 20%
J 2
(3550 2675);
DISPLAY 0.553191 (3550 2675);
DISPLAY INVISIBLE (3550 2675);
FORCEPROP 1 LAST PATH I159
J 2
(3625 2625);
DISPLAY 0.723404 (3625 2625);
DISPLAY INVISIBLE (3625 2625);
FORCEPROP 1 LAST $LOCATION C752
J 0
(3875 2700);
DISPLAY 1.021277 (3875 2700);
DISPLAY INVISIBLE (3875 2700);
FORCEPROP 2 LAST CDS_LOCATION C752
J 0
(3875 2700);
DISPLAY 1.021277 (3875 2700);
DISPLAY INVISIBLE (3875 2700);
FORCEPROP 2 LAST $SEC 1
J 2
(3800 2700);
DISPLAY 0.680851 (3800 2700);
PAINT MONO (3800 2700);
DISPLAY INVISIBLE (3800 2700);
FORCEPROP 2 LAST CDS_SEC 1
J 2
(3800 2700);
DISPLAY 0.680851 (3800 2700);
DISPLAY INVISIBLE (3800 2700);
FORCEADD Q_CAP_DIFFBUS..2
R 2
(3625 2825);
FORCEPROP 1 LAST PART_NUMBER SP_CH4221MEE01
J 2
(3509 2913);
DISPLAY 0.574468 (3509 2913);
PAINT GREEN (3509 2913);
DISPLAY INVISIBLE (3509 2913);
FORCEPROP 2 LAST VALUE DIFF BUS_0.22UF
J 2
(3475 2825);
DISPLAY 0.553191 (3475 2825);
FORCEPROP 1 LAST $LOCATION C750
J 2
(3859 2842);
DISPLAY 0.723404 (3859 2842);
PAINT GREEN (3859 2842);
FORCEPROP 2 LASTPIN (3700 2825) $PN 1
J 0
(3710 2835);
DISPLAY 0.808511 (3710 2835);
FORCEPROP 2 LASTPIN (3550 2825) $PN 2
J 2
(3540 2835);
DISPLAY 0.808511 (3540 2835);
FORCEPROP 2 LAST CDS_LIB pure_quanta
J 2
(3625 2825);
DISPLAY INVISIBLE (3625 2825);
FORCEPROP 1 LAST CDS_LMAN_SYM_OUTLINE -25,50,25,-50
J 2
(3625 2825);
DISPLAY 0.468085 (3625 2825);
PAINT GREEN (3625 2825);
DISPLAY INVISIBLE (3625 2825);
FORCEPROP 1 LAST PIN_NAMES_ROTATE TRUE
J 2
(3625 2825);
DISPLAY 0.489362 (3625 2825);
PAINT GREEN (3625 2825);
DISPLAY INVISIBLE (3625 2825);
FORCEPROP 2 LAST VOLTAGE 6.3V
J 2
(3275 2875);
DISPLAY 0.553191 (3275 2875);
DISPLAY INVISIBLE (3275 2875);
FORCEPROP 1 LAST MATERIAL X6S
J 2
(3634 2904);
DISPLAY 0.574468 (3634 2904);
PAINT GREEN (3634 2904);
DISPLAY INVISIBLE (3634 2904);
FORCEPROP 2 LAST PACK_TYPE C0201
J 2
(3450 2875);
DISPLAY 0.553191 (3450 2875);
DISPLAY INVISIBLE (3450 2875);
FORCEPROP 2 LAST TOLERANCE 20%
J 2
(3550 2875);
DISPLAY 0.553191 (3550 2875);
DISPLAY INVISIBLE (3550 2875);
FORCEPROP 1 LAST PATH I160
J 2
(3625 2825);
DISPLAY 0.723404 (3625 2825);
DISPLAY INVISIBLE (3625 2825);
FORCEPROP 1 LAST $LOCATION C750
J 0
(3875 2900);
DISPLAY 1.021277 (3875 2900);
DISPLAY INVISIBLE (3875 2900);
FORCEPROP 2 LAST CDS_LOCATION C750
J 0
(3875 2900);
DISPLAY 1.021277 (3875 2900);
DISPLAY INVISIBLE (3875 2900);
FORCEPROP 2 LAST $SEC 1
J 2
(3800 2900);
DISPLAY 0.680851 (3800 2900);
PAINT MONO (3800 2900);
DISPLAY INVISIBLE (3800 2900);
FORCEPROP 2 LAST CDS_SEC 1
J 2
(3800 2900);
DISPLAY 0.680851 (3800 2900);
DISPLAY INVISIBLE (3800 2900);
FORCEADD Q_CAP_DIFFBUS..2
R 2
(3625 2775);
FORCEPROP 1 LAST PART_NUMBER SP_CH4221MEE01
J 2
(3509 2863);
DISPLAY 0.574468 (3509 2863);
PAINT GREEN (3509 2863);
DISPLAY INVISIBLE (3509 2863);
FORCEPROP 2 LAST VALUE DIFF BUS_0.22UF
J 2
(3475 2775);
DISPLAY 0.553191 (3475 2775);
FORCEPROP 1 LAST $LOCATION C751
J 2
(3859 2792);
DISPLAY 0.723404 (3859 2792);
PAINT GREEN (3859 2792);
FORCEPROP 2 LASTPIN (3700 2775) $PN 1
J 0
(3710 2785);
DISPLAY 0.808511 (3710 2785);
FORCEPROP 2 LASTPIN (3550 2775) $PN 2
J 2
(3540 2785);
DISPLAY 0.808511 (3540 2785);
FORCEPROP 2 LAST CDS_LIB pure_quanta
J 2
(3625 2775);
DISPLAY INVISIBLE (3625 2775);
FORCEPROP 1 LAST CDS_LMAN_SYM_OUTLINE -25,50,25,-50
J 2
(3625 2775);
DISPLAY 0.468085 (3625 2775);
PAINT GREEN (3625 2775);
DISPLAY INVISIBLE (3625 2775);
FORCEPROP 1 LAST PIN_NAMES_ROTATE TRUE
J 2
(3625 2775);
DISPLAY 0.489362 (3625 2775);
PAINT GREEN (3625 2775);
DISPLAY INVISIBLE (3625 2775);
FORCEPROP 2 LAST VOLTAGE 6.3V
J 2
(3275 2825);
DISPLAY 0.553191 (3275 2825);
DISPLAY INVISIBLE (3275 2825);
FORCEPROP 1 LAST MATERIAL X6S
J 2
(3634 2854);
DISPLAY 0.574468 (3634 2854);
PAINT GREEN (3634 2854);
DISPLAY INVISIBLE (3634 2854);
FORCEPROP 2 LAST PACK_TYPE C0201
J 2
(3450 2825);
DISPLAY 0.553191 (3450 2825);
DISPLAY INVISIBLE (3450 2825);
FORCEPROP 2 LAST TOLERANCE 20%
J 2
(3550 2825);
DISPLAY 0.553191 (3550 2825);
DISPLAY INVISIBLE (3550 2825);
FORCEPROP 1 LAST PATH I161
J 2
(3625 2775);
DISPLAY 0.723404 (3625 2775);
DISPLAY INVISIBLE (3625 2775);
FORCEPROP 1 LAST $LOCATION C751
J 0
(3875 2850);
DISPLAY 1.021277 (3875 2850);
DISPLAY INVISIBLE (3875 2850);
FORCEPROP 2 LAST CDS_LOCATION C751
J 0
(3875 2850);
DISPLAY 1.021277 (3875 2850);
DISPLAY INVISIBLE (3875 2850);
FORCEPROP 2 LAST $SEC 1
J 2
(3800 2850);
DISPLAY 0.680851 (3800 2850);
PAINT MONO (3800 2850);
DISPLAY INVISIBLE (3800 2850);
FORCEPROP 2 LAST CDS_SEC 1
J 2
(3800 2850);
DISPLAY 0.680851 (3800 2850);
DISPLAY INVISIBLE (3800 2850);
FORCEADD Q_CAP_DIFFBUS..2
R 2
(3625 2975);
FORCEPROP 1 LAST PART_NUMBER SP_CH4221MEE01
J 2
(3509 3063);
DISPLAY 0.574468 (3509 3063);
PAINT GREEN (3509 3063);
DISPLAY INVISIBLE (3509 3063);
FORCEPROP 2 LAST VALUE DIFF BUS_0.22UF
J 2
(3475 2975);
DISPLAY 0.553191 (3475 2975);
FORCEPROP 1 LAST $LOCATION C749
J 2
(3859 2992);
DISPLAY 0.723404 (3859 2992);
PAINT GREEN (3859 2992);
FORCEPROP 2 LASTPIN (3700 2975) $PN 1
J 0
(3710 2985);
DISPLAY 0.808511 (3710 2985);
FORCEPROP 2 LASTPIN (3550 2975) $PN 2
J 2
(3540 2985);
DISPLAY 0.808511 (3540 2985);
FORCEPROP 1 LAST CDS_LMAN_SYM_OUTLINE -25,50,25,-50
J 2
(3625 2975);
DISPLAY 0.468085 (3625 2975);
PAINT GREEN (3625 2975);
DISPLAY INVISIBLE (3625 2975);
FORCEPROP 2 LAST CDS_LIB pure_quanta
J 2
(3625 2975);
DISPLAY INVISIBLE (3625 2975);
FORCEPROP 1 LAST PIN_NAMES_ROTATE TRUE
J 2
(3625 2975);
DISPLAY 0.489362 (3625 2975);
PAINT GREEN (3625 2975);
DISPLAY INVISIBLE (3625 2975);
FORCEPROP 2 LAST VOLTAGE 6.3V
J 2
(3275 3025);
DISPLAY 0.553191 (3275 3025);
DISPLAY INVISIBLE (3275 3025);
FORCEPROP 1 LAST MATERIAL X6S
J 2
(3634 3054);
DISPLAY 0.574468 (3634 3054);
PAINT GREEN (3634 3054);
DISPLAY INVISIBLE (3634 3054);
FORCEPROP 2 LAST PACK_TYPE C0201
J 2
(3450 3025);
DISPLAY 0.553191 (3450 3025);
DISPLAY INVISIBLE (3450 3025);
FORCEPROP 2 LAST TOLERANCE 20%
J 2
(3550 3025);
DISPLAY 0.553191 (3550 3025);
DISPLAY INVISIBLE (3550 3025);
FORCEPROP 1 LAST PATH I162
J 2
(3625 2975);
DISPLAY 0.723404 (3625 2975);
DISPLAY INVISIBLE (3625 2975);
FORCEPROP 1 LAST $LOCATION C749
J 0
(3875 3050);
DISPLAY 1.021277 (3875 3050);
DISPLAY INVISIBLE (3875 3050);
FORCEPROP 2 LAST CDS_LOCATION C749
J 0
(3875 3050);
DISPLAY 1.021277 (3875 3050);
DISPLAY INVISIBLE (3875 3050);
FORCEPROP 2 LAST $SEC 1
J 2
(3800 3050);
DISPLAY 0.680851 (3800 3050);
PAINT MONO (3800 3050);
DISPLAY INVISIBLE (3800 3050);
FORCEPROP 2 LAST CDS_SEC 1
J 2
(3800 3050);
DISPLAY 0.680851 (3800 3050);
DISPLAY INVISIBLE (3800 3050);
FORCEADD Q_CAP_DIFFBUS..2
R 2
(3625 3025);
FORCEPROP 1 LAST PART_NUMBER SP_CH4221MEE01
J 2
(3509 3113);
DISPLAY 0.574468 (3509 3113);
PAINT GREEN (3509 3113);
DISPLAY INVISIBLE (3509 3113);
FORCEPROP 2 LAST VALUE DIFF BUS_0.22UF
J 2
(3475 3025);
DISPLAY 0.553191 (3475 3025);
FORCEPROP 1 LAST $LOCATION C748
J 2
(3859 3042);
DISPLAY 0.723404 (3859 3042);
PAINT GREEN (3859 3042);
FORCEPROP 2 LASTPIN (3700 3025) $PN 1
J 0
(3710 3035);
DISPLAY 0.808511 (3710 3035);
FORCEPROP 2 LASTPIN (3550 3025) $PN 2
J 2
(3540 3035);
DISPLAY 0.808511 (3540 3035);
FORCEPROP 1 LAST CDS_LMAN_SYM_OUTLINE -25,50,25,-50
J 2
(3625 3025);
DISPLAY 0.468085 (3625 3025);
PAINT GREEN (3625 3025);
DISPLAY INVISIBLE (3625 3025);
FORCEPROP 2 LAST CDS_LIB pure_quanta
J 2
(3625 3025);
DISPLAY INVISIBLE (3625 3025);
FORCEPROP 1 LAST PIN_NAMES_ROTATE TRUE
J 2
(3625 3025);
DISPLAY 0.489362 (3625 3025);
PAINT GREEN (3625 3025);
DISPLAY INVISIBLE (3625 3025);
FORCEPROP 2 LAST VOLTAGE 6.3V
J 2
(3275 3075);
DISPLAY 0.553191 (3275 3075);
DISPLAY INVISIBLE (3275 3075);
FORCEPROP 1 LAST MATERIAL X6S
J 2
(3634 3104);
DISPLAY 0.574468 (3634 3104);
PAINT GREEN (3634 3104);
DISPLAY INVISIBLE (3634 3104);
FORCEPROP 2 LAST PACK_TYPE C0201
J 2
(3450 3075);
DISPLAY 0.553191 (3450 3075);
DISPLAY INVISIBLE (3450 3075);
FORCEPROP 2 LAST TOLERANCE 20%
J 2
(3550 3075);
DISPLAY 0.553191 (3550 3075);
DISPLAY INVISIBLE (3550 3075);
FORCEPROP 1 LAST PATH I163
J 2
(3625 3025);
DISPLAY 0.723404 (3625 3025);
DISPLAY INVISIBLE (3625 3025);
FORCEPROP 1 LAST $LOCATION C748
J 0
(3875 3100);
DISPLAY 1.021277 (3875 3100);
DISPLAY INVISIBLE (3875 3100);
FORCEPROP 2 LAST CDS_LOCATION C748
J 0
(3875 3100);
DISPLAY 1.021277 (3875 3100);
DISPLAY INVISIBLE (3875 3100);
FORCEPROP 2 LAST $SEC 1
J 2
(3800 3100);
DISPLAY 0.680851 (3800 3100);
PAINT MONO (3800 3100);
DISPLAY INVISIBLE (3800 3100);
FORCEPROP 2 LAST CDS_SEC 1
J 2
(3800 3100);
DISPLAY 0.680851 (3800 3100);
DISPLAY INVISIBLE (3800 3100);
FORCEADD TAP..1
R 2
(2900 3225);
FORCEPROP 3 LASTPIN (2950 3225) SIG_NAME P5E_CPU1_PE2_TX_DN<13>
J 0
(2960 3235);
DISPLAY 0.659574 (2960 3235);
PAINT MONO (2960 3235);
DISPLAY INVISIBLE (2960 3235);
FORCEPROP 1 LASTPIN (2950 3225) BN 13
J 2
(2962 3233);
DISPLAY 0.680851 (2962 3233);
PAINT GREEN (2962 3233);
FORCEPROP 2 LAST CDS_LIB standard
J 0
(2900 3225);
DISPLAY INVISIBLE (2900 3225);
FORCEPROP 1 LAST BODY_TYPE PLUMBING
J 2
(2900 3275);
DISPLAY 0.872340 (2900 3275);
PAINT GREEN (2900 3275);
DISPLAY INVISIBLE (2900 3275);
FORCEPROP 1 LAST HDL_TAP TRUE
J 2
(2575 3100);
DISPLAY 0.872340 (2575 3100);
DISPLAY INVISIBLE (2575 3100);
FORCEPROP 1 LAST PATH I164
J 2
(2902 3225);
DISPLAY 0.872340 (2902 3225);
PAINT GREEN (2902 3225);
DISPLAY INVISIBLE (2902 3225);
FORCEADD TAP..1
R 2
(2900 3425);
FORCEPROP 3 LASTPIN (2950 3425) SIG_NAME P5E_CPU1_PE2_TX_DN<14>
J 0
(2960 3435);
DISPLAY 0.659574 (2960 3435);
PAINT MONO (2960 3435);
DISPLAY INVISIBLE (2960 3435);
FORCEPROP 1 LASTPIN (2950 3425) BN 14
J 2
(2962 3433);
DISPLAY 0.680851 (2962 3433);
PAINT GREEN (2962 3433);
FORCEPROP 2 LAST CDS_LIB standard
J 0
(2900 3425);
DISPLAY INVISIBLE (2900 3425);
FORCEPROP 1 LAST BODY_TYPE PLUMBING
J 2
(2900 3475);
DISPLAY 0.872340 (2900 3475);
PAINT GREEN (2900 3475);
DISPLAY INVISIBLE (2900 3475);
FORCEPROP 1 LAST HDL_TAP TRUE
J 2
(2575 3300);
DISPLAY 0.872340 (2575 3300);
DISPLAY INVISIBLE (2575 3300);
FORCEPROP 1 LAST PATH I165
J 2
(2902 3425);
DISPLAY 0.872340 (2902 3425);
PAINT GREEN (2902 3425);
DISPLAY INVISIBLE (2902 3425);
FORCEADD TAP..1
R 2
(2900 3625);
FORCEPROP 3 LASTPIN (2950 3625) SIG_NAME P5E_CPU1_PE2_TX_DN<15>
J 0
(2960 3635);
DISPLAY 0.659574 (2960 3635);
PAINT MONO (2960 3635);
DISPLAY INVISIBLE (2960 3635);
FORCEPROP 1 LASTPIN (2950 3625) BN 15
J 2
(2962 3633);
DISPLAY 0.680851 (2962 3633);
PAINT GREEN (2962 3633);
FORCEPROP 2 LAST CDS_LIB standard
J 0
(2900 3625);
DISPLAY INVISIBLE (2900 3625);
FORCEPROP 1 LAST BODY_TYPE PLUMBING
J 2
(2900 3675);
DISPLAY 0.872340 (2900 3675);
PAINT GREEN (2900 3675);
DISPLAY INVISIBLE (2900 3675);
FORCEPROP 1 LAST HDL_TAP TRUE
J 2
(2575 3500);
DISPLAY 0.872340 (2575 3500);
DISPLAY INVISIBLE (2575 3500);
FORCEPROP 1 LAST PATH I166
J 2
(2902 3625);
DISPLAY 0.872340 (2902 3625);
PAINT GREEN (2902 3625);
DISPLAY INVISIBLE (2902 3625);
FORCEADD Q_CAP_DIFFBUS..2
R 2
(3625 3175);
FORCEPROP 1 LAST PART_NUMBER SP_CH4221MEE01
J 2
(3509 3263);
DISPLAY 0.574468 (3509 3263);
PAINT GREEN (3509 3263);
DISPLAY INVISIBLE (3509 3263);
FORCEPROP 2 LAST VALUE DIFF BUS_0.22UF
J 2
(3475 3175);
DISPLAY 0.553191 (3475 3175);
FORCEPROP 1 LAST $LOCATION C747
J 2
(3859 3192);
DISPLAY 0.723404 (3859 3192);
PAINT GREEN (3859 3192);
FORCEPROP 2 LASTPIN (3700 3175) $PN 1
J 0
(3710 3185);
DISPLAY 0.808511 (3710 3185);
FORCEPROP 2 LASTPIN (3550 3175) $PN 2
J 2
(3540 3185);
DISPLAY 0.808511 (3540 3185);
FORCEPROP 1 LAST CDS_LMAN_SYM_OUTLINE -25,50,25,-50
J 2
(3625 3175);
DISPLAY 0.468085 (3625 3175);
PAINT GREEN (3625 3175);
DISPLAY INVISIBLE (3625 3175);
FORCEPROP 2 LAST CDS_LIB pure_quanta
J 2
(3625 3175);
DISPLAY INVISIBLE (3625 3175);
FORCEPROP 1 LAST PIN_NAMES_ROTATE TRUE
J 2
(3625 3175);
DISPLAY 0.489362 (3625 3175);
PAINT GREEN (3625 3175);
DISPLAY INVISIBLE (3625 3175);
FORCEPROP 2 LAST VOLTAGE 6.3V
J 2
(3275 3225);
DISPLAY 0.553191 (3275 3225);
DISPLAY INVISIBLE (3275 3225);
FORCEPROP 1 LAST MATERIAL X6S
J 2
(3634 3254);
DISPLAY 0.574468 (3634 3254);
PAINT GREEN (3634 3254);
DISPLAY INVISIBLE (3634 3254);
FORCEPROP 2 LAST PACK_TYPE C0201
J 2
(3450 3225);
DISPLAY 0.553191 (3450 3225);
DISPLAY INVISIBLE (3450 3225);
FORCEPROP 2 LAST TOLERANCE 20%
J 2
(3550 3225);
DISPLAY 0.553191 (3550 3225);
DISPLAY INVISIBLE (3550 3225);
FORCEPROP 1 LAST PATH I167
J 2
(3625 3175);
DISPLAY 0.723404 (3625 3175);
DISPLAY INVISIBLE (3625 3175);
FORCEPROP 1 LAST $LOCATION C747
J 0
(3875 3250);
DISPLAY 1.021277 (3875 3250);
DISPLAY INVISIBLE (3875 3250);
FORCEPROP 2 LAST CDS_LOCATION C747
J 0
(3875 3250);
DISPLAY 1.021277 (3875 3250);
DISPLAY INVISIBLE (3875 3250);
FORCEPROP 2 LAST $SEC 1
J 2
(3800 3250);
DISPLAY 0.680851 (3800 3250);
PAINT MONO (3800 3250);
DISPLAY INVISIBLE (3800 3250);
FORCEPROP 2 LAST CDS_SEC 1
J 2
(3800 3250);
DISPLAY 0.680851 (3800 3250);
DISPLAY INVISIBLE (3800 3250);
FORCEADD Q_CAP_DIFFBUS..2
R 2
(3625 3225);
FORCEPROP 1 LAST PART_NUMBER SP_CH4221MEE01
J 2
(3509 3313);
DISPLAY 0.574468 (3509 3313);
PAINT GREEN (3509 3313);
DISPLAY INVISIBLE (3509 3313);
FORCEPROP 2 LAST VALUE DIFF BUS_0.22UF
J 2
(3475 3225);
DISPLAY 0.553191 (3475 3225);
FORCEPROP 1 LAST $LOCATION C746
J 2
(3859 3242);
DISPLAY 0.723404 (3859 3242);
PAINT GREEN (3859 3242);
FORCEPROP 2 LASTPIN (3700 3225) $PN 1
J 0
(3710 3235);
DISPLAY 0.808511 (3710 3235);
FORCEPROP 2 LASTPIN (3550 3225) $PN 2
J 2
(3540 3235);
DISPLAY 0.808511 (3540 3235);
FORCEPROP 1 LAST CDS_LMAN_SYM_OUTLINE -25,50,25,-50
J 2
(3625 3225);
DISPLAY 0.468085 (3625 3225);
PAINT GREEN (3625 3225);
DISPLAY INVISIBLE (3625 3225);
FORCEPROP 2 LAST CDS_LIB pure_quanta
J 2
(3625 3225);
DISPLAY INVISIBLE (3625 3225);
FORCEPROP 1 LAST PIN_NAMES_ROTATE TRUE
J 2
(3625 3225);
DISPLAY 0.489362 (3625 3225);
PAINT GREEN (3625 3225);
DISPLAY INVISIBLE (3625 3225);
FORCEPROP 2 LAST VOLTAGE 6.3V
J 2
(3275 3275);
DISPLAY 0.553191 (3275 3275);
DISPLAY INVISIBLE (3275 3275);
FORCEPROP 1 LAST MATERIAL X6S
J 2
(3634 3304);
DISPLAY 0.574468 (3634 3304);
PAINT GREEN (3634 3304);
DISPLAY INVISIBLE (3634 3304);
FORCEPROP 2 LAST PACK_TYPE C0201
J 2
(3450 3275);
DISPLAY 0.553191 (3450 3275);
DISPLAY INVISIBLE (3450 3275);
FORCEPROP 2 LAST TOLERANCE 20%
J 2
(3550 3275);
DISPLAY 0.553191 (3550 3275);
DISPLAY INVISIBLE (3550 3275);
FORCEPROP 1 LAST PATH I168
J 2
(3625 3225);
DISPLAY 0.723404 (3625 3225);
DISPLAY INVISIBLE (3625 3225);
FORCEPROP 1 LAST $LOCATION C746
J 0
(3875 3300);
DISPLAY 1.021277 (3875 3300);
DISPLAY INVISIBLE (3875 3300);
FORCEPROP 2 LAST CDS_LOCATION C746
J 0
(3875 3300);
DISPLAY 1.021277 (3875 3300);
DISPLAY INVISIBLE (3875 3300);
FORCEPROP 2 LAST $SEC 1
J 2
(3800 3300);
DISPLAY 0.680851 (3800 3300);
PAINT MONO (3800 3300);
DISPLAY INVISIBLE (3800 3300);
FORCEPROP 2 LAST CDS_SEC 1
J 2
(3800 3300);
DISPLAY 0.680851 (3800 3300);
DISPLAY INVISIBLE (3800 3300);
FORCEADD Q_CAP_DIFFBUS..2
R 2
(3625 3375);
FORCEPROP 1 LAST PART_NUMBER SP_CH4221MEE01
J 2
(3509 3463);
DISPLAY 0.574468 (3509 3463);
PAINT GREEN (3509 3463);
DISPLAY INVISIBLE (3509 3463);
FORCEPROP 2 LAST VALUE DIFF BUS_0.22UF
J 2
(3475 3375);
DISPLAY 0.553191 (3475 3375);
FORCEPROP 1 LAST $LOCATION C745
J 2
(3859 3392);
DISPLAY 0.723404 (3859 3392);
PAINT GREEN (3859 3392);
FORCEPROP 2 LASTPIN (3700 3375) $PN 1
J 0
(3710 3385);
DISPLAY 0.808511 (3710 3385);
FORCEPROP 2 LASTPIN (3550 3375) $PN 2
J 2
(3540 3385);
DISPLAY 0.808511 (3540 3385);
FORCEPROP 1 LAST CDS_LMAN_SYM_OUTLINE -25,50,25,-50
J 2
(3625 3375);
DISPLAY 0.468085 (3625 3375);
PAINT GREEN (3625 3375);
DISPLAY INVISIBLE (3625 3375);
FORCEPROP 2 LAST CDS_LIB pure_quanta
J 2
(3625 3375);
DISPLAY INVISIBLE (3625 3375);
FORCEPROP 1 LAST PIN_NAMES_ROTATE TRUE
J 2
(3625 3375);
DISPLAY 0.489362 (3625 3375);
PAINT GREEN (3625 3375);
DISPLAY INVISIBLE (3625 3375);
FORCEPROP 2 LAST VOLTAGE 6.3V
J 2
(3275 3425);
DISPLAY 0.553191 (3275 3425);
DISPLAY INVISIBLE (3275 3425);
FORCEPROP 1 LAST MATERIAL X6S
J 2
(3634 3454);
DISPLAY 0.574468 (3634 3454);
PAINT GREEN (3634 3454);
DISPLAY INVISIBLE (3634 3454);
FORCEPROP 2 LAST PACK_TYPE C0201
J 2
(3450 3425);
DISPLAY 0.553191 (3450 3425);
DISPLAY INVISIBLE (3450 3425);
FORCEPROP 2 LAST TOLERANCE 20%
J 2
(3550 3425);
DISPLAY 0.553191 (3550 3425);
DISPLAY INVISIBLE (3550 3425);
FORCEPROP 1 LAST PATH I169
J 2
(3625 3375);
DISPLAY 0.723404 (3625 3375);
DISPLAY INVISIBLE (3625 3375);
FORCEPROP 1 LAST $LOCATION C745
J 0
(3875 3450);
DISPLAY 1.021277 (3875 3450);
DISPLAY INVISIBLE (3875 3450);
FORCEPROP 2 LAST CDS_LOCATION C745
J 0
(3875 3450);
DISPLAY 1.021277 (3875 3450);
DISPLAY INVISIBLE (3875 3450);
FORCEPROP 2 LAST $SEC 1
J 2
(3800 3450);
DISPLAY 0.680851 (3800 3450);
PAINT MONO (3800 3450);
DISPLAY INVISIBLE (3800 3450);
FORCEPROP 2 LAST CDS_SEC 1
J 2
(3800 3450);
DISPLAY 0.680851 (3800 3450);
DISPLAY INVISIBLE (3800 3450);
FORCEADD Q_CAP_DIFFBUS..2
R 2
(3625 3425);
FORCEPROP 1 LAST PART_NUMBER SP_CH4221MEE01
J 2
(3509 3513);
DISPLAY 0.574468 (3509 3513);
PAINT GREEN (3509 3513);
DISPLAY INVISIBLE (3509 3513);
FORCEPROP 2 LAST VALUE DIFF BUS_0.22UF
J 2
(3475 3425);
DISPLAY 0.553191 (3475 3425);
FORCEPROP 1 LAST $LOCATION C744
J 2
(3859 3442);
DISPLAY 0.723404 (3859 3442);
PAINT GREEN (3859 3442);
FORCEPROP 2 LASTPIN (3700 3425) $PN 1
J 0
(3710 3435);
DISPLAY 0.808511 (3710 3435);
FORCEPROP 2 LASTPIN (3550 3425) $PN 2
J 2
(3540 3435);
DISPLAY 0.808511 (3540 3435);
FORCEPROP 1 LAST CDS_LMAN_SYM_OUTLINE -25,50,25,-50
J 2
(3625 3425);
DISPLAY 0.468085 (3625 3425);
PAINT GREEN (3625 3425);
DISPLAY INVISIBLE (3625 3425);
FORCEPROP 2 LAST CDS_LIB pure_quanta
J 2
(3625 3425);
DISPLAY INVISIBLE (3625 3425);
FORCEPROP 1 LAST PIN_NAMES_ROTATE TRUE
J 2
(3625 3425);
DISPLAY 0.489362 (3625 3425);
PAINT GREEN (3625 3425);
DISPLAY INVISIBLE (3625 3425);
FORCEPROP 2 LAST VOLTAGE 6.3V
J 2
(3275 3475);
DISPLAY 0.553191 (3275 3475);
DISPLAY INVISIBLE (3275 3475);
FORCEPROP 1 LAST MATERIAL X6S
J 2
(3634 3504);
DISPLAY 0.574468 (3634 3504);
PAINT GREEN (3634 3504);
DISPLAY INVISIBLE (3634 3504);
FORCEPROP 2 LAST PACK_TYPE C0201
J 2
(3450 3475);
DISPLAY 0.553191 (3450 3475);
DISPLAY INVISIBLE (3450 3475);
FORCEPROP 2 LAST TOLERANCE 20%
J 2
(3550 3475);
DISPLAY 0.553191 (3550 3475);
DISPLAY INVISIBLE (3550 3475);
FORCEPROP 1 LAST PATH I170
J 2
(3625 3425);
DISPLAY 0.723404 (3625 3425);
DISPLAY INVISIBLE (3625 3425);
FORCEPROP 1 LAST $LOCATION C744
J 0
(3875 3500);
DISPLAY 1.021277 (3875 3500);
DISPLAY INVISIBLE (3875 3500);
FORCEPROP 2 LAST CDS_LOCATION C744
J 0
(3875 3500);
DISPLAY 1.021277 (3875 3500);
DISPLAY INVISIBLE (3875 3500);
FORCEPROP 2 LAST $SEC 1
J 2
(3800 3500);
DISPLAY 0.680851 (3800 3500);
PAINT MONO (3800 3500);
DISPLAY INVISIBLE (3800 3500);
FORCEPROP 2 LAST CDS_SEC 1
J 2
(3800 3500);
DISPLAY 0.680851 (3800 3500);
DISPLAY INVISIBLE (3800 3500);
FORCEADD Q_CAP_DIFFBUS..2
R 2
(3625 3575);
FORCEPROP 1 LAST PART_NUMBER SP_CH4221MEE01
J 2
(3509 3663);
DISPLAY 0.574468 (3509 3663);
PAINT GREEN (3509 3663);
DISPLAY INVISIBLE (3509 3663);
FORCEPROP 2 LAST VALUE DIFF BUS_0.22UF
J 2
(3475 3575);
DISPLAY 0.553191 (3475 3575);
FORCEPROP 1 LAST $LOCATION C743
J 2
(3859 3592);
DISPLAY 0.723404 (3859 3592);
PAINT GREEN (3859 3592);
FORCEPROP 2 LASTPIN (3700 3575) $PN 1
J 0
(3710 3585);
DISPLAY 0.808511 (3710 3585);
FORCEPROP 2 LASTPIN (3550 3575) $PN 2
J 2
(3540 3585);
DISPLAY 0.808511 (3540 3585);
FORCEPROP 1 LAST CDS_LMAN_SYM_OUTLINE -25,50,25,-50
J 2
(3625 3575);
DISPLAY 0.468085 (3625 3575);
PAINT GREEN (3625 3575);
DISPLAY INVISIBLE (3625 3575);
FORCEPROP 2 LAST CDS_LIB pure_quanta
J 2
(3625 3575);
DISPLAY INVISIBLE (3625 3575);
FORCEPROP 1 LAST PIN_NAMES_ROTATE TRUE
J 2
(3625 3575);
DISPLAY 0.489362 (3625 3575);
PAINT GREEN (3625 3575);
DISPLAY INVISIBLE (3625 3575);
FORCEPROP 2 LAST VOLTAGE 6.3V
J 2
(3275 3625);
DISPLAY 0.553191 (3275 3625);
DISPLAY INVISIBLE (3275 3625);
FORCEPROP 1 LAST MATERIAL X6S
J 2
(3634 3654);
DISPLAY 0.574468 (3634 3654);
PAINT GREEN (3634 3654);
DISPLAY INVISIBLE (3634 3654);
FORCEPROP 2 LAST PACK_TYPE C0201
J 2
(3450 3625);
DISPLAY 0.553191 (3450 3625);
DISPLAY INVISIBLE (3450 3625);
FORCEPROP 2 LAST TOLERANCE 20%
J 2
(3550 3625);
DISPLAY 0.553191 (3550 3625);
DISPLAY INVISIBLE (3550 3625);
FORCEPROP 1 LAST PATH I171
J 2
(3625 3575);
DISPLAY 0.723404 (3625 3575);
DISPLAY INVISIBLE (3625 3575);
FORCEPROP 1 LAST $LOCATION C743
J 0
(3875 3650);
DISPLAY 1.021277 (3875 3650);
DISPLAY INVISIBLE (3875 3650);
FORCEPROP 2 LAST CDS_LOCATION C743
J 0
(3875 3650);
DISPLAY 1.021277 (3875 3650);
DISPLAY INVISIBLE (3875 3650);
FORCEPROP 2 LAST $SEC 1
J 2
(3800 3650);
DISPLAY 0.680851 (3800 3650);
PAINT MONO (3800 3650);
DISPLAY INVISIBLE (3800 3650);
FORCEPROP 2 LAST CDS_SEC 1
J 2
(3800 3650);
DISPLAY 0.680851 (3800 3650);
DISPLAY INVISIBLE (3800 3650);
FORCEADD Q_CAP_DIFFBUS..2
R 2
(3625 3625);
FORCEPROP 1 LAST PART_NUMBER SP_CH4221MEE01
J 2
(3884 3713);
DISPLAY 0.574468 (3884 3713);
PAINT GREEN (3884 3713);
DISPLAY INVISIBLE (3884 3713);
FORCEPROP 2 LAST VOLTAGE 6.3V
J 2
(3875 3775);
DISPLAY 0.553191 (3875 3775);
PAINT GREEN (3875 3775);
FORCEPROP 2 LAST TOLERANCE 20%
J 2
(3725 3775);
DISPLAY 0.553191 (3725 3775);
PAINT GREEN (3725 3775);
FORCEPROP 1 LAST MATERIAL X6S
J 2
(3584 3829);
DISPLAY 0.574468 (3584 3829);
PAINT GREEN (3584 3829);
FORCEPROP 2 LAST PACK_TYPE C0201
J 2
(3625 3775);
DISPLAY 0.553191 (3625 3775);
PAINT GREEN (3625 3775);
FORCEPROP 2 LAST VALUE DIFF BUS_0.22UF
J 2
(3475 3625);
DISPLAY 0.553191 (3475 3625);
FORCEPROP 1 LAST $LOCATION C742
J 2
(3859 3642);
DISPLAY 0.723404 (3859 3642);
PAINT GREEN (3859 3642);
FORCEPROP 2 LASTPIN (3700 3625) $PN 1
J 0
(3710 3635);
DISPLAY 0.808511 (3710 3635);
FORCEPROP 2 LASTPIN (3550 3625) $PN 2
J 2
(3540 3635);
DISPLAY 0.808511 (3540 3635);
FORCEPROP 2 LAST CDS_LIB pure_quanta
J 2
(3625 3625);
DISPLAY INVISIBLE (3625 3625);
FORCEPROP 1 LAST CDS_LMAN_SYM_OUTLINE -25,50,25,-50
J 2
(3625 3625);
DISPLAY 0.468085 (3625 3625);
PAINT GREEN (3625 3625);
DISPLAY INVISIBLE (3625 3625);
FORCEPROP 1 LAST PIN_NAMES_ROTATE TRUE
J 2
(3625 3625);
DISPLAY 0.489362 (3625 3625);
PAINT GREEN (3625 3625);
DISPLAY INVISIBLE (3625 3625);
FORCEPROP 1 LAST PATH I172
J 2
(3625 3625);
DISPLAY 0.723404 (3625 3625);
DISPLAY INVISIBLE (3625 3625);
FORCEPROP 1 LAST $LOCATION C742
J 0
(3875 3700);
DISPLAY 1.021277 (3875 3700);
DISPLAY INVISIBLE (3875 3700);
FORCEPROP 2 LAST CDS_LOCATION C742
J 0
(3600 3875);
DISPLAY 1.021277 (3600 3875);
DISPLAY INVISIBLE (3600 3875);
FORCEPROP 2 LAST $SEC 1
J 2
(3800 3700);
DISPLAY 0.680851 (3800 3700);
PAINT MONO (3800 3700);
DISPLAY INVISIBLE (3800 3700);
FORCEPROP 2 LAST CDS_SEC 1
J 2
(3800 3700);
DISPLAY 0.680851 (3800 3700);
DISPLAY INVISIBLE (3800 3700);
FORCEADD TAP..1
(4175 250);
FORCEPROP 3 LASTPIN (4125 250) SIG_NAME P5E_CPU1_PE2_TX_C_DN<0>
J 0
(4135 260);
DISPLAY 0.659574 (4135 260);
PAINT MONO (4135 260);
DISPLAY INVISIBLE (4135 260);
FORCEPROP 1 LASTPIN (4125 250) BN 0
J 0
(4113 258);
DISPLAY 0.680851 (4113 258);
PAINT GREEN (4113 258);
FORCEPROP 2 LAST CDS_LIB standard
J 0
(4175 250);
DISPLAY INVISIBLE (4175 250);
FORCEPROP 1 LAST BODY_TYPE PLUMBING
J 0
(4175 300);
DISPLAY 0.872340 (4175 300);
PAINT GREEN (4175 300);
DISPLAY INVISIBLE (4175 300);
FORCEPROP 1 LAST HDL_TAP TRUE
J 0
(4500 125);
DISPLAY 0.872340 (4500 125);
DISPLAY INVISIBLE (4500 125);
FORCEPROP 1 LAST PATH I173
J 0
(4173 250);
DISPLAY 0.872340 (4173 250);
PAINT GREEN (4173 250);
DISPLAY INVISIBLE (4173 250);
FORCEADD TAP..1
(4175 450);
FORCEPROP 3 LASTPIN (4125 450) SIG_NAME P5E_CPU1_PE2_TX_C_DN<1>
J 0
(4135 460);
DISPLAY 0.659574 (4135 460);
PAINT MONO (4135 460);
DISPLAY INVISIBLE (4135 460);
FORCEPROP 1 LASTPIN (4125 450) BN 1
J 0
(4113 458);
DISPLAY 0.680851 (4113 458);
PAINT GREEN (4113 458);
FORCEPROP 2 LAST CDS_LIB standard
J 0
(4175 450);
DISPLAY INVISIBLE (4175 450);
FORCEPROP 1 LAST BODY_TYPE PLUMBING
J 0
(4175 500);
DISPLAY 0.872340 (4175 500);
PAINT GREEN (4175 500);
DISPLAY INVISIBLE (4175 500);
FORCEPROP 1 LAST HDL_TAP TRUE
J 0
(4500 325);
DISPLAY 0.872340 (4500 325);
DISPLAY INVISIBLE (4500 325);
FORCEPROP 1 LAST PATH I174
J 0
(4173 450);
DISPLAY 0.872340 (4173 450);
PAINT GREEN (4173 450);
DISPLAY INVISIBLE (4173 450);
FORCEADD TAP..1
(4175 650);
FORCEPROP 3 LASTPIN (4125 650) SIG_NAME P5E_CPU1_PE2_TX_C_DN<2>
J 0
(4135 660);
DISPLAY 0.659574 (4135 660);
PAINT MONO (4135 660);
DISPLAY INVISIBLE (4135 660);
FORCEPROP 1 LASTPIN (4125 650) BN 2
J 0
(4113 658);
DISPLAY 0.680851 (4113 658);
PAINT GREEN (4113 658);
FORCEPROP 2 LAST CDS_LIB standard
J 0
(4175 650);
DISPLAY INVISIBLE (4175 650);
FORCEPROP 1 LAST BODY_TYPE PLUMBING
J 0
(4175 700);
DISPLAY 0.872340 (4175 700);
PAINT GREEN (4175 700);
DISPLAY INVISIBLE (4175 700);
FORCEPROP 1 LAST HDL_TAP TRUE
J 0
(4500 525);
DISPLAY 0.872340 (4500 525);
DISPLAY INVISIBLE (4500 525);
FORCEPROP 1 LAST PATH I175
J 0
(4173 650);
DISPLAY 0.872340 (4173 650);
PAINT GREEN (4173 650);
DISPLAY INVISIBLE (4173 650);
FORCEADD TAP..1
(4175 1050);
FORCEPROP 3 LASTPIN (4125 1050) SIG_NAME P5E_CPU1_PE2_TX_C_DN<4>
J 0
(4135 1060);
DISPLAY 0.659574 (4135 1060);
PAINT MONO (4135 1060);
DISPLAY INVISIBLE (4135 1060);
FORCEPROP 1 LASTPIN (4125 1050) BN 4
J 0
(4113 1058);
DISPLAY 0.680851 (4113 1058);
PAINT GREEN (4113 1058);
FORCEPROP 2 LAST CDS_LIB standard
J 0
(4175 1050);
DISPLAY INVISIBLE (4175 1050);
FORCEPROP 1 LAST BODY_TYPE PLUMBING
J 0
(4175 1100);
DISPLAY 0.872340 (4175 1100);
PAINT GREEN (4175 1100);
DISPLAY INVISIBLE (4175 1100);
FORCEPROP 1 LAST HDL_TAP TRUE
J 0
(4500 925);
DISPLAY 0.872340 (4500 925);
DISPLAY INVISIBLE (4500 925);
FORCEPROP 1 LAST PATH I176
J 0
(4173 1050);
DISPLAY 0.872340 (4173 1050);
PAINT GREEN (4173 1050);
DISPLAY INVISIBLE (4173 1050);
FORCEADD TAP..1
(4175 850);
FORCEPROP 3 LASTPIN (4125 850) SIG_NAME P5E_CPU1_PE2_TX_C_DN<3>
J 0
(4135 860);
DISPLAY 0.659574 (4135 860);
PAINT MONO (4135 860);
DISPLAY INVISIBLE (4135 860);
FORCEPROP 1 LASTPIN (4125 850) BN 3
J 0
(4113 858);
DISPLAY 0.680851 (4113 858);
PAINT GREEN (4113 858);
FORCEPROP 2 LAST CDS_LIB standard
J 0
(4175 850);
DISPLAY INVISIBLE (4175 850);
FORCEPROP 1 LAST BODY_TYPE PLUMBING
J 0
(4175 900);
DISPLAY 0.872340 (4175 900);
PAINT GREEN (4175 900);
DISPLAY INVISIBLE (4175 900);
FORCEPROP 1 LAST HDL_TAP TRUE
J 0
(4500 725);
DISPLAY 0.872340 (4500 725);
DISPLAY INVISIBLE (4500 725);
FORCEPROP 1 LAST PATH I177
J 0
(4173 850);
DISPLAY 0.872340 (4173 850);
PAINT GREEN (4173 850);
DISPLAY INVISIBLE (4173 850);
FORCEADD TAP..1
(4375 200);
FORCEPROP 3 LASTPIN (4325 200) SIG_NAME P5E_CPU1_PE2_TX_C_DP<0>
J 0
(4335 210);
DISPLAY 0.659574 (4335 210);
PAINT MONO (4335 210);
DISPLAY INVISIBLE (4335 210);
FORCEPROP 1 LASTPIN (4325 200) BN 0
J 0
(4313 208);
DISPLAY 0.680851 (4313 208);
PAINT GREEN (4313 208);
FORCEPROP 2 LAST CDS_LIB standard
J 0
(4375 200);
DISPLAY INVISIBLE (4375 200);
FORCEPROP 1 LAST BODY_TYPE PLUMBING
J 0
(4375 250);
DISPLAY 0.872340 (4375 250);
PAINT GREEN (4375 250);
DISPLAY INVISIBLE (4375 250);
FORCEPROP 1 LAST HDL_TAP TRUE
J 0
(4700 75);
DISPLAY 0.872340 (4700 75);
DISPLAY INVISIBLE (4700 75);
FORCEPROP 1 LAST PATH I178
J 0
(4373 200);
DISPLAY 0.872340 (4373 200);
PAINT GREEN (4373 200);
DISPLAY INVISIBLE (4373 200);
FORCEADD TAP..1
(4375 400);
FORCEPROP 3 LASTPIN (4325 400) SIG_NAME P5E_CPU1_PE2_TX_C_DP<1>
J 0
(4335 410);
DISPLAY 0.659574 (4335 410);
PAINT MONO (4335 410);
DISPLAY INVISIBLE (4335 410);
FORCEPROP 1 LASTPIN (4325 400) BN 1
J 0
(4313 408);
DISPLAY 0.680851 (4313 408);
PAINT GREEN (4313 408);
FORCEPROP 2 LAST CDS_LIB standard
J 0
(4375 400);
DISPLAY INVISIBLE (4375 400);
FORCEPROP 1 LAST BODY_TYPE PLUMBING
J 0
(4375 450);
DISPLAY 0.872340 (4375 450);
PAINT GREEN (4375 450);
DISPLAY INVISIBLE (4375 450);
FORCEPROP 1 LAST HDL_TAP TRUE
J 0
(4700 275);
DISPLAY 0.872340 (4700 275);
DISPLAY INVISIBLE (4700 275);
FORCEPROP 1 LAST PATH I179
J 0
(4373 400);
DISPLAY 0.872340 (4373 400);
PAINT GREEN (4373 400);
DISPLAY INVISIBLE (4373 400);
FORCEADD TAP..1
(4375 600);
FORCEPROP 3 LASTPIN (4325 600) SIG_NAME P5E_CPU1_PE2_TX_C_DP<2>
J 0
(4335 610);
DISPLAY 0.659574 (4335 610);
PAINT MONO (4335 610);
DISPLAY INVISIBLE (4335 610);
FORCEPROP 1 LASTPIN (4325 600) BN 2
J 0
(4313 608);
DISPLAY 0.680851 (4313 608);
PAINT GREEN (4313 608);
FORCEPROP 2 LAST CDS_LIB standard
J 0
(4375 600);
DISPLAY INVISIBLE (4375 600);
FORCEPROP 1 LAST BODY_TYPE PLUMBING
J 0
(4375 650);
DISPLAY 0.872340 (4375 650);
PAINT GREEN (4375 650);
DISPLAY INVISIBLE (4375 650);
FORCEPROP 1 LAST HDL_TAP TRUE
J 0
(4700 475);
DISPLAY 0.872340 (4700 475);
DISPLAY INVISIBLE (4700 475);
FORCEPROP 1 LAST PATH I180
J 0
(4373 600);
DISPLAY 0.872340 (4373 600);
PAINT GREEN (4373 600);
DISPLAY INVISIBLE (4373 600);
FORCEADD TAP..1
(4375 800);
FORCEPROP 3 LASTPIN (4325 800) SIG_NAME P5E_CPU1_PE2_TX_C_DP<3>
J 0
(4335 810);
DISPLAY 0.659574 (4335 810);
PAINT MONO (4335 810);
DISPLAY INVISIBLE (4335 810);
FORCEPROP 1 LASTPIN (4325 800) BN 3
J 0
(4313 808);
DISPLAY 0.680851 (4313 808);
PAINT GREEN (4313 808);
FORCEPROP 2 LAST CDS_LIB standard
J 0
(4375 800);
DISPLAY INVISIBLE (4375 800);
FORCEPROP 1 LAST BODY_TYPE PLUMBING
J 0
(4375 850);
DISPLAY 0.872340 (4375 850);
PAINT GREEN (4375 850);
DISPLAY INVISIBLE (4375 850);
FORCEPROP 1 LAST HDL_TAP TRUE
J 0
(4700 675);
DISPLAY 0.872340 (4700 675);
DISPLAY INVISIBLE (4700 675);
FORCEPROP 1 LAST PATH I181
J 0
(4373 800);
DISPLAY 0.872340 (4373 800);
PAINT GREEN (4373 800);
DISPLAY INVISIBLE (4373 800);
FORCEADD TAP..1
(4375 1000);
FORCEPROP 3 LASTPIN (4325 1000) SIG_NAME P5E_CPU1_PE2_TX_C_DP<4>
J 0
(4335 1010);
DISPLAY 0.659574 (4335 1010);
PAINT MONO (4335 1010);
DISPLAY INVISIBLE (4335 1010);
FORCEPROP 1 LASTPIN (4325 1000) BN 4
J 0
(4313 1008);
DISPLAY 0.680851 (4313 1008);
PAINT GREEN (4313 1008);
FORCEPROP 2 LAST CDS_LIB standard
J 0
(4375 1000);
DISPLAY INVISIBLE (4375 1000);
FORCEPROP 1 LAST BODY_TYPE PLUMBING
J 0
(4375 1050);
DISPLAY 0.872340 (4375 1050);
PAINT GREEN (4375 1050);
DISPLAY INVISIBLE (4375 1050);
FORCEPROP 1 LAST HDL_TAP TRUE
J 0
(4700 875);
DISPLAY 0.872340 (4700 875);
DISPLAY INVISIBLE (4700 875);
FORCEPROP 1 LAST PATH I182
J 0
(4373 1000);
DISPLAY 0.872340 (4373 1000);
PAINT GREEN (4373 1000);
DISPLAY INVISIBLE (4373 1000);
FORCEADD TAP..1
(4175 1250);
FORCEPROP 3 LASTPIN (4125 1250) SIG_NAME P5E_CPU1_PE2_TX_C_DN<5>
J 0
(4135 1260);
DISPLAY 0.659574 (4135 1260);
PAINT MONO (4135 1260);
DISPLAY INVISIBLE (4135 1260);
FORCEPROP 1 LASTPIN (4125 1250) BN 5
J 0
(4113 1258);
DISPLAY 0.680851 (4113 1258);
PAINT GREEN (4113 1258);
FORCEPROP 2 LAST CDS_LIB standard
J 0
(4175 1250);
DISPLAY INVISIBLE (4175 1250);
FORCEPROP 1 LAST BODY_TYPE PLUMBING
J 0
(4175 1300);
DISPLAY 0.872340 (4175 1300);
PAINT GREEN (4175 1300);
DISPLAY INVISIBLE (4175 1300);
FORCEPROP 1 LAST HDL_TAP TRUE
J 0
(4500 1125);
DISPLAY 0.872340 (4500 1125);
DISPLAY INVISIBLE (4500 1125);
FORCEPROP 1 LAST PATH I183
J 0
(4173 1250);
DISPLAY 0.872340 (4173 1250);
PAINT GREEN (4173 1250);
DISPLAY INVISIBLE (4173 1250);
FORCEADD TAP..1
(4175 1450);
FORCEPROP 3 LASTPIN (4125 1450) SIG_NAME P5E_CPU1_PE2_TX_C_DN<6>
J 0
(4135 1460);
DISPLAY 0.659574 (4135 1460);
PAINT MONO (4135 1460);
DISPLAY INVISIBLE (4135 1460);
FORCEPROP 1 LASTPIN (4125 1450) BN 6
J 0
(4113 1458);
DISPLAY 0.680851 (4113 1458);
PAINT GREEN (4113 1458);
FORCEPROP 2 LAST CDS_LIB standard
J 0
(4175 1450);
DISPLAY INVISIBLE (4175 1450);
FORCEPROP 1 LAST BODY_TYPE PLUMBING
J 0
(4175 1500);
DISPLAY 0.872340 (4175 1500);
PAINT GREEN (4175 1500);
DISPLAY INVISIBLE (4175 1500);
FORCEPROP 1 LAST HDL_TAP TRUE
J 0
(4500 1325);
DISPLAY 0.872340 (4500 1325);
DISPLAY INVISIBLE (4500 1325);
FORCEPROP 1 LAST PATH I184
J 0
(4173 1450);
DISPLAY 0.872340 (4173 1450);
PAINT GREEN (4173 1450);
DISPLAY INVISIBLE (4173 1450);
FORCEADD TAP..1
(4175 1650);
FORCEPROP 3 LASTPIN (4125 1650) SIG_NAME P5E_CPU1_PE2_TX_C_DN<7>
J 0
(4135 1660);
DISPLAY 0.659574 (4135 1660);
PAINT MONO (4135 1660);
DISPLAY INVISIBLE (4135 1660);
FORCEPROP 1 LASTPIN (4125 1650) BN 7
J 0
(4113 1658);
DISPLAY 0.680851 (4113 1658);
PAINT GREEN (4113 1658);
FORCEPROP 2 LAST CDS_LIB standard
J 0
(4175 1650);
DISPLAY INVISIBLE (4175 1650);
FORCEPROP 1 LAST BODY_TYPE PLUMBING
J 0
(4175 1700);
DISPLAY 0.872340 (4175 1700);
PAINT GREEN (4175 1700);
DISPLAY INVISIBLE (4175 1700);
FORCEPROP 1 LAST HDL_TAP TRUE
J 0
(4500 1525);
DISPLAY 0.872340 (4500 1525);
DISPLAY INVISIBLE (4500 1525);
FORCEPROP 1 LAST PATH I185
J 0
(4173 1650);
DISPLAY 0.872340 (4173 1650);
PAINT GREEN (4173 1650);
DISPLAY INVISIBLE (4173 1650);
FORCEADD TAP..1
(4375 1200);
FORCEPROP 3 LASTPIN (4325 1200) SIG_NAME P5E_CPU1_PE2_TX_C_DP<5>
J 0
(4335 1210);
DISPLAY 0.659574 (4335 1210);
PAINT MONO (4335 1210);
DISPLAY INVISIBLE (4335 1210);
FORCEPROP 1 LASTPIN (4325 1200) BN 5
J 0
(4313 1208);
DISPLAY 0.680851 (4313 1208);
PAINT GREEN (4313 1208);
FORCEPROP 2 LAST CDS_LIB standard
J 0
(4375 1200);
DISPLAY INVISIBLE (4375 1200);
FORCEPROP 1 LAST BODY_TYPE PLUMBING
J 0
(4375 1250);
DISPLAY 0.872340 (4375 1250);
PAINT GREEN (4375 1250);
DISPLAY INVISIBLE (4375 1250);
FORCEPROP 1 LAST HDL_TAP TRUE
J 0
(4700 1075);
DISPLAY 0.872340 (4700 1075);
DISPLAY INVISIBLE (4700 1075);
FORCEPROP 1 LAST PATH I186
J 0
(4373 1200);
DISPLAY 0.872340 (4373 1200);
PAINT GREEN (4373 1200);
DISPLAY INVISIBLE (4373 1200);
FORCEADD TAP..1
(4375 1400);
FORCEPROP 3 LASTPIN (4325 1400) SIG_NAME P5E_CPU1_PE2_TX_C_DP<6>
J 0
(4335 1410);
DISPLAY 0.659574 (4335 1410);
PAINT MONO (4335 1410);
DISPLAY INVISIBLE (4335 1410);
FORCEPROP 1 LASTPIN (4325 1400) BN 6
J 0
(4313 1408);
DISPLAY 0.680851 (4313 1408);
PAINT GREEN (4313 1408);
FORCEPROP 2 LAST CDS_LIB standard
J 0
(4375 1400);
DISPLAY INVISIBLE (4375 1400);
FORCEPROP 1 LAST BODY_TYPE PLUMBING
J 0
(4375 1450);
DISPLAY 0.872340 (4375 1450);
PAINT GREEN (4375 1450);
DISPLAY INVISIBLE (4375 1450);
FORCEPROP 1 LAST HDL_TAP TRUE
J 0
(4700 1275);
DISPLAY 0.872340 (4700 1275);
DISPLAY INVISIBLE (4700 1275);
FORCEPROP 1 LAST PATH I187
J 0
(4373 1400);
DISPLAY 0.872340 (4373 1400);
PAINT GREEN (4373 1400);
DISPLAY INVISIBLE (4373 1400);
FORCEADD TAP..1
(4375 1600);
FORCEPROP 3 LASTPIN (4325 1600) SIG_NAME P5E_CPU1_PE2_TX_C_DP<7>
J 0
(4335 1610);
DISPLAY 0.659574 (4335 1610);
PAINT MONO (4335 1610);
DISPLAY INVISIBLE (4335 1610);
FORCEPROP 1 LASTPIN (4325 1600) BN 7
J 0
(4313 1608);
DISPLAY 0.680851 (4313 1608);
PAINT GREEN (4313 1608);
FORCEPROP 2 LAST CDS_LIB standard
J 0
(4375 1600);
DISPLAY INVISIBLE (4375 1600);
FORCEPROP 1 LAST BODY_TYPE PLUMBING
J 0
(4375 1650);
DISPLAY 0.872340 (4375 1650);
PAINT GREEN (4375 1650);
DISPLAY INVISIBLE (4375 1650);
FORCEPROP 1 LAST HDL_TAP TRUE
J 0
(4700 1475);
DISPLAY 0.872340 (4700 1475);
DISPLAY INVISIBLE (4700 1475);
FORCEPROP 1 LAST PATH I188
J 0
(4373 1600);
DISPLAY 0.872340 (4373 1600);
PAINT GREEN (4373 1600);
DISPLAY INVISIBLE (4373 1600);
FORCEADD OFFPAGE..2
(5375 1625);
FORCEPROP 2 LAST $XR0 140 
J 0
(5564 1625);
DISPLAY 0.638298 (5564 1625);
PAINT MONO (5564 1625);
FORCEPROP 2 LAST CDS_LIB standard
J 0
(5375 1625);
DISPLAY INVISIBLE (5375 1625);
FORCEPROP 1 LAST OFFPAGE TRUE
J 0
(5700 1500);
DISPLAY 0.872340 (5700 1500);
DISPLAY INVISIBLE (5700 1500);
FORCEPROP 1 LAST COMMENT_BODY TRUE
J 0
(5330 1530);
DISPLAY 0.872340 (5330 1530);
PAINT GREEN (5330 1530);
DISPLAY INVISIBLE (5330 1530);
FORCEPROP 2 LAST PATH I189
J 0
(5550 1700);
DISPLAY 1.021277 (5550 1700);
DISPLAY INVISIBLE (5550 1700);
FORCEADD OFFPAGE..2
(5375 1675);
FORCEPROP 2 LAST $XR0 140 
J 0
(5564 1675);
DISPLAY 0.638298 (5564 1675);
PAINT MONO (5564 1675);
FORCEPROP 2 LAST CDS_LIB standard
J 0
(5375 1675);
DISPLAY INVISIBLE (5375 1675);
FORCEPROP 1 LAST OFFPAGE TRUE
J 0
(5700 1550);
DISPLAY 0.872340 (5700 1550);
DISPLAY INVISIBLE (5700 1550);
FORCEPROP 1 LAST COMMENT_BODY TRUE
J 0
(5330 1580);
DISPLAY 0.872340 (5330 1580);
PAINT GREEN (5330 1580);
DISPLAY INVISIBLE (5330 1580);
FORCEPROP 2 LAST PATH I190
J 0
(5550 1750);
DISPLAY 1.021277 (5550 1750);
DISPLAY INVISIBLE (5550 1750);
FORCEADD TAP..1
(4175 2225);
FORCEPROP 3 LASTPIN (4125 2225) SIG_NAME P5E_CPU1_PE2_TX_C_DN<8>
J 0
(4135 2235);
DISPLAY 0.659574 (4135 2235);
PAINT MONO (4135 2235);
DISPLAY INVISIBLE (4135 2235);
FORCEPROP 1 LASTPIN (4125 2225) BN 8
J 0
(4113 2233);
DISPLAY 0.680851 (4113 2233);
PAINT GREEN (4113 2233);
FORCEPROP 2 LAST CDS_LIB standard
J 0
(4175 2225);
DISPLAY INVISIBLE (4175 2225);
FORCEPROP 1 LAST BODY_TYPE PLUMBING
J 0
(4175 2275);
DISPLAY 0.872340 (4175 2275);
PAINT GREEN (4175 2275);
DISPLAY INVISIBLE (4175 2275);
FORCEPROP 1 LAST HDL_TAP TRUE
J 0
(4500 2100);
DISPLAY 0.872340 (4500 2100);
DISPLAY INVISIBLE (4500 2100);
FORCEPROP 1 LAST PATH I191
J 0
(4173 2225);
DISPLAY 0.872340 (4173 2225);
PAINT GREEN (4173 2225);
DISPLAY INVISIBLE (4173 2225);
FORCEADD TAP..1
(4175 2425);
FORCEPROP 3 LASTPIN (4125 2425) SIG_NAME P5E_CPU1_PE2_TX_C_DN<9>
J 0
(4135 2435);
DISPLAY 0.659574 (4135 2435);
PAINT MONO (4135 2435);
DISPLAY INVISIBLE (4135 2435);
FORCEPROP 1 LASTPIN (4125 2425) BN 9
J 0
(4113 2433);
DISPLAY 0.680851 (4113 2433);
PAINT GREEN (4113 2433);
FORCEPROP 2 LAST CDS_LIB standard
J 0
(4175 2425);
DISPLAY INVISIBLE (4175 2425);
FORCEPROP 1 LAST BODY_TYPE PLUMBING
J 0
(4175 2475);
DISPLAY 0.872340 (4175 2475);
PAINT GREEN (4175 2475);
DISPLAY INVISIBLE (4175 2475);
FORCEPROP 1 LAST HDL_TAP TRUE
J 0
(4500 2300);
DISPLAY 0.872340 (4500 2300);
DISPLAY INVISIBLE (4500 2300);
FORCEPROP 1 LAST PATH I192
J 0
(4173 2425);
DISPLAY 0.872340 (4173 2425);
PAINT GREEN (4173 2425);
DISPLAY INVISIBLE (4173 2425);
FORCEADD TAP..1
(4175 2625);
FORCEPROP 3 LASTPIN (4125 2625) SIG_NAME P5E_CPU1_PE2_TX_C_DN<10>
J 0
(4135 2635);
DISPLAY 0.659574 (4135 2635);
PAINT MONO (4135 2635);
DISPLAY INVISIBLE (4135 2635);
FORCEPROP 1 LASTPIN (4125 2625) BN 10
J 0
(4113 2633);
DISPLAY 0.680851 (4113 2633);
PAINT GREEN (4113 2633);
FORCEPROP 2 LAST CDS_LIB standard
J 0
(4175 2625);
DISPLAY INVISIBLE (4175 2625);
FORCEPROP 1 LAST BODY_TYPE PLUMBING
J 0
(4175 2675);
DISPLAY 0.872340 (4175 2675);
PAINT GREEN (4175 2675);
DISPLAY INVISIBLE (4175 2675);
FORCEPROP 1 LAST HDL_TAP TRUE
J 0
(4500 2500);
DISPLAY 0.872340 (4500 2500);
DISPLAY INVISIBLE (4500 2500);
FORCEPROP 1 LAST PATH I193
J 0
(4173 2625);
DISPLAY 0.872340 (4173 2625);
PAINT GREEN (4173 2625);
DISPLAY INVISIBLE (4173 2625);
FORCEADD TAP..1
(4175 2825);
FORCEPROP 3 LASTPIN (4125 2825) SIG_NAME P5E_CPU1_PE2_TX_C_DN<11>
J 0
(4135 2835);
DISPLAY 0.659574 (4135 2835);
PAINT MONO (4135 2835);
DISPLAY INVISIBLE (4135 2835);
FORCEPROP 1 LASTPIN (4125 2825) BN 11
J 0
(4113 2833);
DISPLAY 0.680851 (4113 2833);
PAINT GREEN (4113 2833);
FORCEPROP 2 LAST CDS_LIB standard
J 0
(4175 2825);
DISPLAY INVISIBLE (4175 2825);
FORCEPROP 1 LAST BODY_TYPE PLUMBING
J 0
(4175 2875);
DISPLAY 0.872340 (4175 2875);
PAINT GREEN (4175 2875);
DISPLAY INVISIBLE (4175 2875);
FORCEPROP 1 LAST HDL_TAP TRUE
J 0
(4500 2700);
DISPLAY 0.872340 (4500 2700);
DISPLAY INVISIBLE (4500 2700);
FORCEPROP 1 LAST PATH I194
J 0
(4173 2825);
DISPLAY 0.872340 (4173 2825);
PAINT GREEN (4173 2825);
DISPLAY INVISIBLE (4173 2825);
FORCEADD TAP..1
(4175 3025);
FORCEPROP 3 LASTPIN (4125 3025) SIG_NAME P5E_CPU1_PE2_TX_C_DN<12>
J 0
(4135 3035);
DISPLAY 0.659574 (4135 3035);
PAINT MONO (4135 3035);
DISPLAY INVISIBLE (4135 3035);
FORCEPROP 1 LASTPIN (4125 3025) BN 12
J 0
(4113 3033);
DISPLAY 0.680851 (4113 3033);
PAINT GREEN (4113 3033);
FORCEPROP 2 LAST CDS_LIB standard
J 0
(4175 3025);
DISPLAY INVISIBLE (4175 3025);
FORCEPROP 1 LAST BODY_TYPE PLUMBING
J 0
(4175 3075);
DISPLAY 0.872340 (4175 3075);
PAINT GREEN (4175 3075);
DISPLAY INVISIBLE (4175 3075);
FORCEPROP 1 LAST HDL_TAP TRUE
J 0
(4500 2900);
DISPLAY 0.872340 (4500 2900);
DISPLAY INVISIBLE (4500 2900);
FORCEPROP 1 LAST PATH I195
J 0
(4173 3025);
DISPLAY 0.872340 (4173 3025);
PAINT GREEN (4173 3025);
DISPLAY INVISIBLE (4173 3025);
FORCEADD TAP..1
(4375 2175);
FORCEPROP 3 LASTPIN (4325 2175) SIG_NAME P5E_CPU1_PE2_TX_C_DP<8>
J 0
(4335 2185);
DISPLAY 0.659574 (4335 2185);
PAINT MONO (4335 2185);
DISPLAY INVISIBLE (4335 2185);
FORCEPROP 1 LASTPIN (4325 2175) BN 8
J 0
(4313 2183);
DISPLAY 0.680851 (4313 2183);
PAINT GREEN (4313 2183);
FORCEPROP 2 LAST CDS_LIB standard
J 0
(4375 2175);
DISPLAY INVISIBLE (4375 2175);
FORCEPROP 1 LAST BODY_TYPE PLUMBING
J 0
(4375 2225);
DISPLAY 0.872340 (4375 2225);
PAINT GREEN (4375 2225);
DISPLAY INVISIBLE (4375 2225);
FORCEPROP 1 LAST HDL_TAP TRUE
J 0
(4700 2050);
DISPLAY 0.872340 (4700 2050);
DISPLAY INVISIBLE (4700 2050);
FORCEPROP 1 LAST PATH I196
J 0
(4373 2175);
DISPLAY 0.872340 (4373 2175);
PAINT GREEN (4373 2175);
DISPLAY INVISIBLE (4373 2175);
FORCEADD TAP..1
(4375 2375);
FORCEPROP 3 LASTPIN (4325 2375) SIG_NAME P5E_CPU1_PE2_TX_C_DP<9>
J 0
(4335 2385);
DISPLAY 0.659574 (4335 2385);
PAINT MONO (4335 2385);
DISPLAY INVISIBLE (4335 2385);
FORCEPROP 1 LASTPIN (4325 2375) BN 9
J 0
(4313 2383);
DISPLAY 0.680851 (4313 2383);
PAINT GREEN (4313 2383);
FORCEPROP 2 LAST CDS_LIB standard
J 0
(4375 2375);
DISPLAY INVISIBLE (4375 2375);
FORCEPROP 1 LAST BODY_TYPE PLUMBING
J 0
(4375 2425);
DISPLAY 0.872340 (4375 2425);
PAINT GREEN (4375 2425);
DISPLAY INVISIBLE (4375 2425);
FORCEPROP 1 LAST HDL_TAP TRUE
J 0
(4700 2250);
DISPLAY 0.872340 (4700 2250);
DISPLAY INVISIBLE (4700 2250);
FORCEPROP 1 LAST PATH I197
J 0
(4373 2375);
DISPLAY 0.872340 (4373 2375);
PAINT GREEN (4373 2375);
DISPLAY INVISIBLE (4373 2375);
FORCEADD TAP..1
(4375 2575);
FORCEPROP 3 LASTPIN (4325 2575) SIG_NAME P5E_CPU1_PE2_TX_C_DP<10>
J 0
(4335 2585);
DISPLAY 0.659574 (4335 2585);
PAINT MONO (4335 2585);
DISPLAY INVISIBLE (4335 2585);
FORCEPROP 1 LASTPIN (4325 2575) BN 10
J 0
(4313 2583);
DISPLAY 0.680851 (4313 2583);
PAINT GREEN (4313 2583);
FORCEPROP 2 LAST CDS_LIB standard
J 0
(4375 2575);
DISPLAY INVISIBLE (4375 2575);
FORCEPROP 1 LAST BODY_TYPE PLUMBING
J 0
(4375 2625);
DISPLAY 0.872340 (4375 2625);
PAINT GREEN (4375 2625);
DISPLAY INVISIBLE (4375 2625);
FORCEPROP 1 LAST HDL_TAP TRUE
J 0
(4700 2450);
DISPLAY 0.872340 (4700 2450);
DISPLAY INVISIBLE (4700 2450);
FORCEPROP 1 LAST PATH I198
J 0
(4373 2575);
DISPLAY 0.872340 (4373 2575);
PAINT GREEN (4373 2575);
DISPLAY INVISIBLE (4373 2575);
FORCEADD TAP..1
(4375 2775);
FORCEPROP 3 LASTPIN (4325 2775) SIG_NAME P5E_CPU1_PE2_TX_C_DP<11>
J 0
(4335 2785);
DISPLAY 0.659574 (4335 2785);
PAINT MONO (4335 2785);
DISPLAY INVISIBLE (4335 2785);
FORCEPROP 1 LASTPIN (4325 2775) BN 11
J 0
(4313 2783);
DISPLAY 0.680851 (4313 2783);
PAINT GREEN (4313 2783);
FORCEPROP 2 LAST CDS_LIB standard
J 0
(4375 2775);
DISPLAY INVISIBLE (4375 2775);
FORCEPROP 1 LAST BODY_TYPE PLUMBING
J 0
(4375 2825);
DISPLAY 0.872340 (4375 2825);
PAINT GREEN (4375 2825);
DISPLAY INVISIBLE (4375 2825);
FORCEPROP 1 LAST HDL_TAP TRUE
J 0
(4700 2650);
DISPLAY 0.872340 (4700 2650);
DISPLAY INVISIBLE (4700 2650);
FORCEPROP 1 LAST PATH I199
J 0
(4373 2775);
DISPLAY 0.872340 (4373 2775);
PAINT GREEN (4373 2775);
DISPLAY INVISIBLE (4373 2775);
FORCEADD TAP..1
(4375 2975);
FORCEPROP 3 LASTPIN (4325 2975) SIG_NAME P5E_CPU1_PE2_TX_C_DP<12>
J 0
(4335 2985);
DISPLAY 0.659574 (4335 2985);
PAINT MONO (4335 2985);
DISPLAY INVISIBLE (4335 2985);
FORCEPROP 1 LASTPIN (4325 2975) BN 12
J 0
(4313 2983);
DISPLAY 0.680851 (4313 2983);
PAINT GREEN (4313 2983);
FORCEPROP 2 LAST CDS_LIB standard
J 0
(4375 2975);
DISPLAY INVISIBLE (4375 2975);
FORCEPROP 1 LAST BODY_TYPE PLUMBING
J 0
(4375 3025);
DISPLAY 0.872340 (4375 3025);
PAINT GREEN (4375 3025);
DISPLAY INVISIBLE (4375 3025);
FORCEPROP 1 LAST HDL_TAP TRUE
J 0
(4700 2850);
DISPLAY 0.872340 (4700 2850);
DISPLAY INVISIBLE (4700 2850);
FORCEPROP 1 LAST PATH I200
J 0
(4373 2975);
DISPLAY 0.872340 (4373 2975);
PAINT GREEN (4373 2975);
DISPLAY INVISIBLE (4373 2975);
FORCEADD TAP..1
(4175 3225);
FORCEPROP 3 LASTPIN (4125 3225) SIG_NAME P5E_CPU1_PE2_TX_C_DN<13>
J 0
(4135 3235);
DISPLAY 0.659574 (4135 3235);
PAINT MONO (4135 3235);
DISPLAY INVISIBLE (4135 3235);
FORCEPROP 1 LASTPIN (4125 3225) BN 13
J 0
(4113 3233);
DISPLAY 0.680851 (4113 3233);
PAINT GREEN (4113 3233);
FORCEPROP 2 LAST CDS_LIB standard
J 0
(4175 3225);
DISPLAY INVISIBLE (4175 3225);
FORCEPROP 1 LAST BODY_TYPE PLUMBING
J 0
(4175 3275);
DISPLAY 0.872340 (4175 3275);
PAINT GREEN (4175 3275);
DISPLAY INVISIBLE (4175 3275);
FORCEPROP 1 LAST HDL_TAP TRUE
J 0
(4500 3100);
DISPLAY 0.872340 (4500 3100);
DISPLAY INVISIBLE (4500 3100);
FORCEPROP 1 LAST PATH I201
J 0
(4173 3225);
DISPLAY 0.872340 (4173 3225);
PAINT GREEN (4173 3225);
DISPLAY INVISIBLE (4173 3225);
FORCEADD TAP..1
(4175 3625);
FORCEPROP 3 LASTPIN (4125 3625) SIG_NAME P5E_CPU1_PE2_TX_C_DN<15>
J 0
(4135 3635);
DISPLAY 0.659574 (4135 3635);
PAINT MONO (4135 3635);
DISPLAY INVISIBLE (4135 3635);
FORCEPROP 1 LASTPIN (4125 3625) BN 15
J 0
(4113 3633);
DISPLAY 0.680851 (4113 3633);
PAINT GREEN (4113 3633);
FORCEPROP 2 LAST CDS_LIB standard
J 0
(4175 3625);
DISPLAY INVISIBLE (4175 3625);
FORCEPROP 1 LAST BODY_TYPE PLUMBING
J 0
(4175 3675);
DISPLAY 0.872340 (4175 3675);
PAINT GREEN (4175 3675);
DISPLAY INVISIBLE (4175 3675);
FORCEPROP 1 LAST HDL_TAP TRUE
J 0
(4500 3500);
DISPLAY 0.872340 (4500 3500);
DISPLAY INVISIBLE (4500 3500);
FORCEPROP 1 LAST PATH I202
J 0
(4173 3625);
DISPLAY 0.872340 (4173 3625);
PAINT GREEN (4173 3625);
DISPLAY INVISIBLE (4173 3625);
FORCEADD TAP..1
(4175 3425);
FORCEPROP 3 LASTPIN (4125 3425) SIG_NAME P5E_CPU1_PE2_TX_C_DN<14>
J 0
(4135 3435);
DISPLAY 0.659574 (4135 3435);
PAINT MONO (4135 3435);
DISPLAY INVISIBLE (4135 3435);
FORCEPROP 1 LASTPIN (4125 3425) BN 14
J 0
(4113 3433);
DISPLAY 0.680851 (4113 3433);
PAINT GREEN (4113 3433);
FORCEPROP 2 LAST CDS_LIB standard
J 0
(4175 3425);
DISPLAY INVISIBLE (4175 3425);
FORCEPROP 1 LAST BODY_TYPE PLUMBING
J 0
(4175 3475);
DISPLAY 0.872340 (4175 3475);
PAINT GREEN (4175 3475);
DISPLAY INVISIBLE (4175 3475);
FORCEPROP 1 LAST HDL_TAP TRUE
J 0
(4500 3300);
DISPLAY 0.872340 (4500 3300);
DISPLAY INVISIBLE (4500 3300);
FORCEPROP 1 LAST PATH I203
J 0
(4173 3425);
DISPLAY 0.872340 (4173 3425);
PAINT GREEN (4173 3425);
DISPLAY INVISIBLE (4173 3425);
FORCEADD TAP..1
(4375 3175);
FORCEPROP 3 LASTPIN (4325 3175) SIG_NAME P5E_CPU1_PE2_TX_C_DP<13>
J 0
(4335 3185);
DISPLAY 0.659574 (4335 3185);
PAINT MONO (4335 3185);
DISPLAY INVISIBLE (4335 3185);
FORCEPROP 1 LASTPIN (4325 3175) BN 13
J 0
(4313 3183);
DISPLAY 0.680851 (4313 3183);
PAINT GREEN (4313 3183);
FORCEPROP 2 LAST CDS_LIB standard
J 0
(4375 3175);
DISPLAY INVISIBLE (4375 3175);
FORCEPROP 1 LAST BODY_TYPE PLUMBING
J 0
(4375 3225);
DISPLAY 0.872340 (4375 3225);
PAINT GREEN (4375 3225);
DISPLAY INVISIBLE (4375 3225);
FORCEPROP 1 LAST HDL_TAP TRUE
J 0
(4700 3050);
DISPLAY 0.872340 (4700 3050);
DISPLAY INVISIBLE (4700 3050);
FORCEPROP 1 LAST PATH I204
J 0
(4373 3175);
DISPLAY 0.872340 (4373 3175);
PAINT GREEN (4373 3175);
DISPLAY INVISIBLE (4373 3175);
FORCEADD TAP..1
(4375 3375);
FORCEPROP 3 LASTPIN (4325 3375) SIG_NAME P5E_CPU1_PE2_TX_C_DP<14>
J 0
(4335 3385);
DISPLAY 0.659574 (4335 3385);
PAINT MONO (4335 3385);
DISPLAY INVISIBLE (4335 3385);
FORCEPROP 1 LASTPIN (4325 3375) BN 14
J 0
(4313 3383);
DISPLAY 0.680851 (4313 3383);
PAINT GREEN (4313 3383);
FORCEPROP 2 LAST CDS_LIB standard
J 0
(4375 3375);
DISPLAY INVISIBLE (4375 3375);
FORCEPROP 1 LAST BODY_TYPE PLUMBING
J 0
(4375 3425);
DISPLAY 0.872340 (4375 3425);
PAINT GREEN (4375 3425);
DISPLAY INVISIBLE (4375 3425);
FORCEPROP 1 LAST HDL_TAP TRUE
J 0
(4700 3250);
DISPLAY 0.872340 (4700 3250);
DISPLAY INVISIBLE (4700 3250);
FORCEPROP 1 LAST PATH I205
J 0
(4373 3375);
DISPLAY 0.872340 (4373 3375);
PAINT GREEN (4373 3375);
DISPLAY INVISIBLE (4373 3375);
FORCEADD TAP..1
(4375 3575);
FORCEPROP 3 LASTPIN (4325 3575) SIG_NAME P5E_CPU1_PE2_TX_C_DP<15>
J 0
(4335 3585);
DISPLAY 0.659574 (4335 3585);
PAINT MONO (4335 3585);
DISPLAY INVISIBLE (4335 3585);
FORCEPROP 1 LASTPIN (4325 3575) BN 15
J 0
(4313 3583);
DISPLAY 0.680851 (4313 3583);
PAINT GREEN (4313 3583);
FORCEPROP 2 LAST CDS_LIB standard
J 0
(4375 3575);
DISPLAY INVISIBLE (4375 3575);
FORCEPROP 1 LAST BODY_TYPE PLUMBING
J 0
(4375 3625);
DISPLAY 0.872340 (4375 3625);
PAINT GREEN (4375 3625);
DISPLAY INVISIBLE (4375 3625);
FORCEPROP 1 LAST HDL_TAP TRUE
J 0
(4700 3450);
DISPLAY 0.872340 (4700 3450);
DISPLAY INVISIBLE (4700 3450);
FORCEPROP 1 LAST PATH I206
J 0
(4373 3575);
DISPLAY 0.872340 (4373 3575);
PAINT GREEN (4373 3575);
DISPLAY INVISIBLE (4373 3575);
FORCEADD OFFPAGE..2
(5375 3650);
FORCEPROP 2 LAST $XR0 141 
J 0
(5564 3650);
DISPLAY 0.638298 (5564 3650);
PAINT MONO (5564 3650);
FORCEPROP 2 LAST CDS_LIB standard
J 0
(5375 3650);
DISPLAY INVISIBLE (5375 3650);
FORCEPROP 1 LAST OFFPAGE TRUE
J 0
(5700 3525);
DISPLAY 0.872340 (5700 3525);
DISPLAY INVISIBLE (5700 3525);
FORCEPROP 1 LAST COMMENT_BODY TRUE
J 0
(5330 3555);
DISPLAY 0.872340 (5330 3555);
PAINT GREEN (5330 3555);
DISPLAY INVISIBLE (5330 3555);
FORCEPROP 2 LAST PATH I207
J 0
(5550 3725);
DISPLAY 1.021277 (5550 3725);
DISPLAY INVISIBLE (5550 3725);
FORCEADD OFFPAGE..2
(5375 3600);
FORCEPROP 2 LAST $XR0 141 
J 0
(5564 3600);
DISPLAY 0.638298 (5564 3600);
PAINT MONO (5564 3600);
FORCEPROP 2 LAST CDS_LIB standard
J 0
(5375 3600);
DISPLAY INVISIBLE (5375 3600);
FORCEPROP 1 LAST OFFPAGE TRUE
J 0
(5700 3475);
DISPLAY 0.872340 (5700 3475);
DISPLAY INVISIBLE (5700 3475);
FORCEPROP 1 LAST COMMENT_BODY TRUE
J 0
(5330 3505);
DISPLAY 0.872340 (5330 3505);
PAINT GREEN (5330 3505);
DISPLAY INVISIBLE (5330 3505);
FORCEPROP 2 LAST PATH I208
J 0
(5550 3675);
DISPLAY 1.021277 (5550 3675);
DISPLAY INVISIBLE (5550 3675);
FORCEADD OFFPAGE..1
(-2875 1650);
FORCEPROP 2 LAST $XR0 60 
J 0
(-3096 1650);
DISPLAY 0.638298 (-3096 1650);
PAINT MONO (-3096 1650);
FORCEPROP 2 LAST CDS_LIB standard
J 0
(-2875 1650);
DISPLAY INVISIBLE (-2875 1650);
FORCEPROP 1 LAST OFFPAGE TRUE
J 0
(-2550 1525);
DISPLAY 0.872340 (-2550 1525);
DISPLAY INVISIBLE (-2550 1525);
FORCEPROP 1 LAST COMMENT_BODY TRUE
J 0
(-2750 1550);
DISPLAY 0.872340 (-2750 1550);
PAINT GREEN (-2750 1550);
DISPLAY INVISIBLE (-2750 1550);
FORCEPROP 2 LAST PATH I209
J 0
(-3150 1700);
DISPLAY 1.021277 (-3150 1700);
DISPLAY INVISIBLE (-3150 1700);
FORCEADD OFFPAGE..1
(-2875 1600);
FORCEPROP 2 LAST $XR0 60 
J 0
(-3096 1600);
DISPLAY 0.638298 (-3096 1600);
PAINT MONO (-3096 1600);
FORCEPROP 2 LAST CDS_LIB standard
J 0
(-2875 1600);
DISPLAY INVISIBLE (-2875 1600);
FORCEPROP 1 LAST OFFPAGE TRUE
J 0
(-2550 1475);
DISPLAY 0.872340 (-2550 1475);
DISPLAY INVISIBLE (-2550 1475);
FORCEPROP 1 LAST COMMENT_BODY TRUE
J 0
(-2750 1500);
DISPLAY 0.872340 (-2750 1500);
PAINT GREEN (-2750 1500);
DISPLAY INVISIBLE (-2750 1500);
FORCEPROP 2 LAST PATH I210
J 0
(-3150 1650);
DISPLAY 1.021277 (-3150 1650);
DISPLAY INVISIBLE (-3150 1650);
FORCEADD OFFPAGE..1
(-2875 3575);
FORCEPROP 2 LAST $XR0 60 
J 0
(-3096 3575);
DISPLAY 0.638298 (-3096 3575);
PAINT MONO (-3096 3575);
FORCEPROP 2 LAST CDS_LIB standard
J 0
(-2875 3575);
DISPLAY INVISIBLE (-2875 3575);
FORCEPROP 1 LAST OFFPAGE TRUE
J 0
(-2550 3450);
DISPLAY 0.872340 (-2550 3450);
DISPLAY INVISIBLE (-2550 3450);
FORCEPROP 1 LAST COMMENT_BODY TRUE
J 0
(-2750 3475);
DISPLAY 0.872340 (-2750 3475);
PAINT GREEN (-2750 3475);
DISPLAY INVISIBLE (-2750 3475);
FORCEPROP 2 LAST PATH I211
J 0
(-3150 3625);
DISPLAY 1.021277 (-3150 3625);
DISPLAY INVISIBLE (-3150 3625);
FORCEADD OFFPAGE..1
(-2875 3625);
FORCEPROP 2 LAST $XR0 60 
J 0
(-3096 3625);
DISPLAY 0.638298 (-3096 3625);
PAINT MONO (-3096 3625);
FORCEPROP 2 LAST CDS_LIB standard
J 0
(-2875 3625);
DISPLAY INVISIBLE (-2875 3625);
FORCEPROP 1 LAST OFFPAGE TRUE
J 0
(-2550 3500);
DISPLAY 0.872340 (-2550 3500);
DISPLAY INVISIBLE (-2550 3500);
FORCEPROP 1 LAST COMMENT_BODY TRUE
J 0
(-2750 3525);
DISPLAY 0.872340 (-2750 3525);
PAINT GREEN (-2750 3525);
DISPLAY INVISIBLE (-2750 3525);
FORCEPROP 2 LAST PATH I212
J 0
(-3150 3675);
DISPLAY 1.021277 (-3150 3675);
DISPLAY INVISIBLE (-3150 3675);
FORCEADD TAP..1
R 2
(-1925 175);
FORCEPROP 3 LASTPIN (-1875 175) SIG_NAME P5E_CPU1_PE0_TX_DP<0>
J 0
(-1865 185);
DISPLAY 0.659574 (-1865 185);
PAINT MONO (-1865 185);
DISPLAY INVISIBLE (-1865 185);
FORCEPROP 1 LASTPIN (-1875 175) BN 0
J 2
(-1863 183);
DISPLAY 0.680851 (-1863 183);
PAINT GREEN (-1863 183);
FORCEPROP 2 LAST CDS_LIB standard
J 0
(-1925 175);
DISPLAY INVISIBLE (-1925 175);
FORCEPROP 1 LAST BODY_TYPE PLUMBING
J 2
(-1925 225);
DISPLAY 0.872340 (-1925 225);
PAINT GREEN (-1925 225);
DISPLAY INVISIBLE (-1925 225);
FORCEPROP 1 LAST HDL_TAP TRUE
J 2
(-2250 50);
DISPLAY 0.872340 (-2250 50);
DISPLAY INVISIBLE (-2250 50);
FORCEPROP 1 LAST PATH I213
J 2
(-1923 175);
DISPLAY 0.872340 (-1923 175);
PAINT GREEN (-1923 175);
DISPLAY INVISIBLE (-1923 175);
FORCEADD TAP..1
R 2
(-1925 375);
FORCEPROP 3 LASTPIN (-1875 375) SIG_NAME P5E_CPU1_PE0_TX_DP<1>
J 0
(-1865 385);
DISPLAY 0.659574 (-1865 385);
PAINT MONO (-1865 385);
DISPLAY INVISIBLE (-1865 385);
FORCEPROP 1 LASTPIN (-1875 375) BN 1
J 2
(-1863 383);
DISPLAY 0.680851 (-1863 383);
PAINT GREEN (-1863 383);
FORCEPROP 2 LAST CDS_LIB standard
J 0
(-1925 375);
DISPLAY INVISIBLE (-1925 375);
FORCEPROP 1 LAST BODY_TYPE PLUMBING
J 2
(-1925 425);
DISPLAY 0.872340 (-1925 425);
PAINT GREEN (-1925 425);
DISPLAY INVISIBLE (-1925 425);
FORCEPROP 1 LAST HDL_TAP TRUE
J 2
(-2250 250);
DISPLAY 0.872340 (-2250 250);
DISPLAY INVISIBLE (-2250 250);
FORCEPROP 1 LAST PATH I214
J 2
(-1923 375);
DISPLAY 0.872340 (-1923 375);
PAINT GREEN (-1923 375);
DISPLAY INVISIBLE (-1923 375);
FORCEADD TAP..1
R 2
(-1675 225);
FORCEPROP 3 LASTPIN (-1625 225) SIG_NAME P5E_CPU1_PE0_TX_DN<0>
J 0
(-1615 235);
DISPLAY 0.659574 (-1615 235);
PAINT MONO (-1615 235);
DISPLAY INVISIBLE (-1615 235);
FORCEPROP 1 LASTPIN (-1625 225) BN 0
J 2
(-1613 233);
DISPLAY 0.680851 (-1613 233);
PAINT GREEN (-1613 233);
FORCEPROP 2 LAST CDS_LIB standard
J 0
(-1675 225);
DISPLAY INVISIBLE (-1675 225);
FORCEPROP 1 LAST BODY_TYPE PLUMBING
J 2
(-1675 275);
DISPLAY 0.872340 (-1675 275);
PAINT GREEN (-1675 275);
DISPLAY INVISIBLE (-1675 275);
FORCEPROP 1 LAST HDL_TAP TRUE
J 2
(-2000 100);
DISPLAY 0.872340 (-2000 100);
DISPLAY INVISIBLE (-2000 100);
FORCEPROP 1 LAST PATH I215
J 2
(-1673 225);
DISPLAY 0.872340 (-1673 225);
PAINT GREEN (-1673 225);
DISPLAY INVISIBLE (-1673 225);
FORCEADD TAP..1
R 2
(-1675 425);
FORCEPROP 3 LASTPIN (-1625 425) SIG_NAME P5E_CPU1_PE0_TX_DN<1>
J 0
(-1615 435);
DISPLAY 0.659574 (-1615 435);
PAINT MONO (-1615 435);
DISPLAY INVISIBLE (-1615 435);
FORCEPROP 1 LASTPIN (-1625 425) BN 1
J 2
(-1613 433);
DISPLAY 0.680851 (-1613 433);
PAINT GREEN (-1613 433);
FORCEPROP 2 LAST CDS_LIB standard
J 0
(-1675 425);
DISPLAY INVISIBLE (-1675 425);
FORCEPROP 1 LAST BODY_TYPE PLUMBING
J 2
(-1675 475);
DISPLAY 0.872340 (-1675 475);
PAINT GREEN (-1675 475);
DISPLAY INVISIBLE (-1675 475);
FORCEPROP 1 LAST HDL_TAP TRUE
J 2
(-2000 300);
DISPLAY 0.872340 (-2000 300);
DISPLAY INVISIBLE (-2000 300);
FORCEPROP 1 LAST PATH I216
J 2
(-1673 425);
DISPLAY 0.872340 (-1673 425);
PAINT GREEN (-1673 425);
DISPLAY INVISIBLE (-1673 425);
FORCEADD TAP..1
R 2
(-1925 575);
FORCEPROP 3 LASTPIN (-1875 575) SIG_NAME P5E_CPU1_PE0_TX_DP<2>
J 0
(-1865 585);
DISPLAY 0.659574 (-1865 585);
PAINT MONO (-1865 585);
DISPLAY INVISIBLE (-1865 585);
FORCEPROP 1 LASTPIN (-1875 575) BN 2
J 2
(-1863 583);
DISPLAY 0.680851 (-1863 583);
PAINT GREEN (-1863 583);
FORCEPROP 2 LAST CDS_LIB standard
J 0
(-1925 575);
DISPLAY INVISIBLE (-1925 575);
FORCEPROP 1 LAST BODY_TYPE PLUMBING
J 2
(-1925 625);
DISPLAY 0.872340 (-1925 625);
PAINT GREEN (-1925 625);
DISPLAY INVISIBLE (-1925 625);
FORCEPROP 1 LAST HDL_TAP TRUE
J 2
(-2250 450);
DISPLAY 0.872340 (-2250 450);
DISPLAY INVISIBLE (-2250 450);
FORCEPROP 1 LAST PATH I217
J 2
(-1923 575);
DISPLAY 0.872340 (-1923 575);
PAINT GREEN (-1923 575);
DISPLAY INVISIBLE (-1923 575);
FORCEADD TAP..1
R 2
(-1925 775);
FORCEPROP 3 LASTPIN (-1875 775) SIG_NAME P5E_CPU1_PE0_TX_DP<3>
J 0
(-1865 785);
DISPLAY 0.659574 (-1865 785);
PAINT MONO (-1865 785);
DISPLAY INVISIBLE (-1865 785);
FORCEPROP 1 LASTPIN (-1875 775) BN 3
J 2
(-1863 783);
DISPLAY 0.680851 (-1863 783);
PAINT GREEN (-1863 783);
FORCEPROP 2 LAST CDS_LIB standard
J 0
(-1925 775);
DISPLAY INVISIBLE (-1925 775);
FORCEPROP 1 LAST BODY_TYPE PLUMBING
J 2
(-1925 825);
DISPLAY 0.872340 (-1925 825);
PAINT GREEN (-1925 825);
DISPLAY INVISIBLE (-1925 825);
FORCEPROP 1 LAST HDL_TAP TRUE
J 2
(-2250 650);
DISPLAY 0.872340 (-2250 650);
DISPLAY INVISIBLE (-2250 650);
FORCEPROP 1 LAST PATH I218
J 2
(-1923 775);
DISPLAY 0.872340 (-1923 775);
PAINT GREEN (-1923 775);
DISPLAY INVISIBLE (-1923 775);
FORCEADD TAP..1
R 2
(-1925 975);
FORCEPROP 3 LASTPIN (-1875 975) SIG_NAME P5E_CPU1_PE0_TX_DP<4>
J 0
(-1865 985);
DISPLAY 0.659574 (-1865 985);
PAINT MONO (-1865 985);
DISPLAY INVISIBLE (-1865 985);
FORCEPROP 1 LASTPIN (-1875 975) BN 4
J 2
(-1863 983);
DISPLAY 0.680851 (-1863 983);
PAINT GREEN (-1863 983);
FORCEPROP 2 LAST CDS_LIB standard
J 0
(-1925 975);
DISPLAY INVISIBLE (-1925 975);
FORCEPROP 1 LAST BODY_TYPE PLUMBING
J 2
(-1925 1025);
DISPLAY 0.872340 (-1925 1025);
PAINT GREEN (-1925 1025);
DISPLAY INVISIBLE (-1925 1025);
FORCEPROP 1 LAST HDL_TAP TRUE
J 2
(-2250 850);
DISPLAY 0.872340 (-2250 850);
DISPLAY INVISIBLE (-2250 850);
FORCEPROP 1 LAST PATH I219
J 2
(-1923 975);
DISPLAY 0.872340 (-1923 975);
PAINT GREEN (-1923 975);
DISPLAY INVISIBLE (-1923 975);
FORCEADD TAP..1
R 2
(-1675 625);
FORCEPROP 3 LASTPIN (-1625 625) SIG_NAME P5E_CPU1_PE0_TX_DN<2>
J 0
(-1615 635);
DISPLAY 0.659574 (-1615 635);
PAINT MONO (-1615 635);
DISPLAY INVISIBLE (-1615 635);
FORCEPROP 1 LASTPIN (-1625 625) BN 2
J 2
(-1613 633);
DISPLAY 0.680851 (-1613 633);
PAINT GREEN (-1613 633);
FORCEPROP 2 LAST CDS_LIB standard
J 0
(-1675 625);
DISPLAY INVISIBLE (-1675 625);
FORCEPROP 1 LAST BODY_TYPE PLUMBING
J 2
(-1675 675);
DISPLAY 0.872340 (-1675 675);
PAINT GREEN (-1675 675);
DISPLAY INVISIBLE (-1675 675);
FORCEPROP 1 LAST HDL_TAP TRUE
J 2
(-2000 500);
DISPLAY 0.872340 (-2000 500);
DISPLAY INVISIBLE (-2000 500);
FORCEPROP 1 LAST PATH I220
J 2
(-1673 625);
DISPLAY 0.872340 (-1673 625);
PAINT GREEN (-1673 625);
DISPLAY INVISIBLE (-1673 625);
FORCEADD TAP..1
R 2
(-1675 825);
FORCEPROP 3 LASTPIN (-1625 825) SIG_NAME P5E_CPU1_PE0_TX_DN<3>
J 0
(-1615 835);
DISPLAY 0.659574 (-1615 835);
PAINT MONO (-1615 835);
DISPLAY INVISIBLE (-1615 835);
FORCEPROP 1 LASTPIN (-1625 825) BN 3
J 2
(-1613 833);
DISPLAY 0.680851 (-1613 833);
PAINT GREEN (-1613 833);
FORCEPROP 2 LAST CDS_LIB standard
J 0
(-1675 825);
DISPLAY INVISIBLE (-1675 825);
FORCEPROP 1 LAST BODY_TYPE PLUMBING
J 2
(-1675 875);
DISPLAY 0.872340 (-1675 875);
PAINT GREEN (-1675 875);
DISPLAY INVISIBLE (-1675 875);
FORCEPROP 1 LAST HDL_TAP TRUE
J 2
(-2000 700);
DISPLAY 0.872340 (-2000 700);
DISPLAY INVISIBLE (-2000 700);
FORCEPROP 1 LAST PATH I221
J 2
(-1673 825);
DISPLAY 0.872340 (-1673 825);
PAINT GREEN (-1673 825);
DISPLAY INVISIBLE (-1673 825);
FORCEADD TAP..1
R 2
(-1925 1175);
FORCEPROP 3 LASTPIN (-1875 1175) SIG_NAME P5E_CPU1_PE0_TX_DP<5>
J 0
(-1865 1185);
DISPLAY 0.659574 (-1865 1185);
PAINT MONO (-1865 1185);
DISPLAY INVISIBLE (-1865 1185);
FORCEPROP 1 LASTPIN (-1875 1175) BN 5
J 2
(-1863 1183);
DISPLAY 0.680851 (-1863 1183);
PAINT GREEN (-1863 1183);
FORCEPROP 2 LAST CDS_LIB standard
J 0
(-1925 1175);
DISPLAY INVISIBLE (-1925 1175);
FORCEPROP 1 LAST BODY_TYPE PLUMBING
J 2
(-1925 1225);
DISPLAY 0.872340 (-1925 1225);
PAINT GREEN (-1925 1225);
DISPLAY INVISIBLE (-1925 1225);
FORCEPROP 1 LAST HDL_TAP TRUE
J 2
(-2250 1050);
DISPLAY 0.872340 (-2250 1050);
DISPLAY INVISIBLE (-2250 1050);
FORCEPROP 1 LAST PATH I222
J 2
(-1923 1175);
DISPLAY 0.872340 (-1923 1175);
PAINT GREEN (-1923 1175);
DISPLAY INVISIBLE (-1923 1175);
FORCEADD TAP..1
R 2
(-1925 1375);
FORCEPROP 3 LASTPIN (-1875 1375) SIG_NAME P5E_CPU1_PE0_TX_DP<6>
J 0
(-1865 1385);
DISPLAY 0.659574 (-1865 1385);
PAINT MONO (-1865 1385);
DISPLAY INVISIBLE (-1865 1385);
FORCEPROP 1 LASTPIN (-1875 1375) BN 6
J 2
(-1863 1383);
DISPLAY 0.680851 (-1863 1383);
PAINT GREEN (-1863 1383);
FORCEPROP 2 LAST CDS_LIB standard
J 0
(-1925 1375);
DISPLAY INVISIBLE (-1925 1375);
FORCEPROP 1 LAST BODY_TYPE PLUMBING
J 2
(-1925 1425);
DISPLAY 0.872340 (-1925 1425);
PAINT GREEN (-1925 1425);
DISPLAY INVISIBLE (-1925 1425);
FORCEPROP 1 LAST HDL_TAP TRUE
J 2
(-2250 1250);
DISPLAY 0.872340 (-2250 1250);
DISPLAY INVISIBLE (-2250 1250);
FORCEPROP 1 LAST PATH I223
J 2
(-1923 1375);
DISPLAY 0.872340 (-1923 1375);
PAINT GREEN (-1923 1375);
DISPLAY INVISIBLE (-1923 1375);
FORCEADD TAP..1
R 2
(-1675 1225);
FORCEPROP 3 LASTPIN (-1625 1225) SIG_NAME P5E_CPU1_PE0_TX_DN<5>
J 0
(-1615 1235);
DISPLAY 0.659574 (-1615 1235);
PAINT MONO (-1615 1235);
DISPLAY INVISIBLE (-1615 1235);
FORCEPROP 1 LASTPIN (-1625 1225) BN 5
J 2
(-1613 1233);
DISPLAY 0.680851 (-1613 1233);
PAINT GREEN (-1613 1233);
FORCEPROP 2 LAST CDS_LIB standard
J 0
(-1675 1225);
DISPLAY INVISIBLE (-1675 1225);
FORCEPROP 1 LAST BODY_TYPE PLUMBING
J 2
(-1675 1275);
DISPLAY 0.872340 (-1675 1275);
PAINT GREEN (-1675 1275);
DISPLAY INVISIBLE (-1675 1275);
FORCEPROP 1 LAST HDL_TAP TRUE
J 2
(-2000 1100);
DISPLAY 0.872340 (-2000 1100);
DISPLAY INVISIBLE (-2000 1100);
FORCEPROP 1 LAST PATH I224
J 2
(-1673 1225);
DISPLAY 0.872340 (-1673 1225);
PAINT GREEN (-1673 1225);
DISPLAY INVISIBLE (-1673 1225);
FORCEADD TAP..1
R 2
(-1675 1025);
FORCEPROP 3 LASTPIN (-1625 1025) SIG_NAME P5E_CPU1_PE0_TX_DN<4>
J 0
(-1615 1035);
DISPLAY 0.659574 (-1615 1035);
PAINT MONO (-1615 1035);
DISPLAY INVISIBLE (-1615 1035);
FORCEPROP 1 LASTPIN (-1625 1025) BN 4
J 2
(-1613 1033);
DISPLAY 0.680851 (-1613 1033);
PAINT GREEN (-1613 1033);
FORCEPROP 2 LAST CDS_LIB standard
J 0
(-1675 1025);
DISPLAY INVISIBLE (-1675 1025);
FORCEPROP 1 LAST BODY_TYPE PLUMBING
J 2
(-1675 1075);
DISPLAY 0.872340 (-1675 1075);
PAINT GREEN (-1675 1075);
DISPLAY INVISIBLE (-1675 1075);
FORCEPROP 1 LAST HDL_TAP TRUE
J 2
(-2000 900);
DISPLAY 0.872340 (-2000 900);
DISPLAY INVISIBLE (-2000 900);
FORCEPROP 1 LAST PATH I225
J 2
(-1673 1025);
DISPLAY 0.872340 (-1673 1025);
PAINT GREEN (-1673 1025);
DISPLAY INVISIBLE (-1673 1025);
FORCEADD TAP..1
R 2
(-1675 1425);
FORCEPROP 3 LASTPIN (-1625 1425) SIG_NAME P5E_CPU1_PE0_TX_DN<6>
J 0
(-1615 1435);
DISPLAY 0.659574 (-1615 1435);
PAINT MONO (-1615 1435);
DISPLAY INVISIBLE (-1615 1435);
FORCEPROP 1 LASTPIN (-1625 1425) BN 6
J 2
(-1613 1433);
DISPLAY 0.680851 (-1613 1433);
PAINT GREEN (-1613 1433);
FORCEPROP 2 LAST CDS_LIB standard
J 0
(-1675 1425);
DISPLAY INVISIBLE (-1675 1425);
FORCEPROP 1 LAST BODY_TYPE PLUMBING
J 2
(-1675 1475);
DISPLAY 0.872340 (-1675 1475);
PAINT GREEN (-1675 1475);
DISPLAY INVISIBLE (-1675 1475);
FORCEPROP 1 LAST HDL_TAP TRUE
J 2
(-2000 1300);
DISPLAY 0.872340 (-2000 1300);
DISPLAY INVISIBLE (-2000 1300);
FORCEPROP 1 LAST PATH I226
J 2
(-1673 1425);
DISPLAY 0.872340 (-1673 1425);
PAINT GREEN (-1673 1425);
DISPLAY INVISIBLE (-1673 1425);
FORCEADD TAP..1
R 2
(-1925 1575);
FORCEPROP 3 LASTPIN (-1875 1575) SIG_NAME P5E_CPU1_PE0_TX_DP<7>
J 0
(-1865 1585);
DISPLAY 0.659574 (-1865 1585);
PAINT MONO (-1865 1585);
DISPLAY INVISIBLE (-1865 1585);
FORCEPROP 1 LASTPIN (-1875 1575) BN 7
J 2
(-1863 1583);
DISPLAY 0.680851 (-1863 1583);
PAINT GREEN (-1863 1583);
FORCEPROP 2 LAST CDS_LIB standard
J 0
(-1925 1575);
DISPLAY INVISIBLE (-1925 1575);
FORCEPROP 1 LAST BODY_TYPE PLUMBING
J 2
(-1925 1625);
DISPLAY 0.872340 (-1925 1625);
PAINT GREEN (-1925 1625);
DISPLAY INVISIBLE (-1925 1625);
FORCEPROP 1 LAST HDL_TAP TRUE
J 2
(-2250 1450);
DISPLAY 0.872340 (-2250 1450);
DISPLAY INVISIBLE (-2250 1450);
FORCEPROP 1 LAST PATH I227
J 2
(-1923 1575);
DISPLAY 0.872340 (-1923 1575);
PAINT GREEN (-1923 1575);
DISPLAY INVISIBLE (-1923 1575);
FORCEADD TAP..1
R 2
(-1675 1625);
FORCEPROP 3 LASTPIN (-1625 1625) SIG_NAME P5E_CPU1_PE0_TX_DN<7>
J 0
(-1615 1635);
DISPLAY 0.659574 (-1615 1635);
PAINT MONO (-1615 1635);
DISPLAY INVISIBLE (-1615 1635);
FORCEPROP 1 LASTPIN (-1625 1625) BN 7
J 2
(-1613 1633);
DISPLAY 0.680851 (-1613 1633);
PAINT GREEN (-1613 1633);
FORCEPROP 2 LAST CDS_LIB standard
J 0
(-1675 1625);
DISPLAY INVISIBLE (-1675 1625);
FORCEPROP 1 LAST BODY_TYPE PLUMBING
J 2
(-1675 1675);
DISPLAY 0.872340 (-1675 1675);
PAINT GREEN (-1675 1675);
DISPLAY INVISIBLE (-1675 1675);
FORCEPROP 1 LAST HDL_TAP TRUE
J 2
(-2000 1500);
DISPLAY 0.872340 (-2000 1500);
DISPLAY INVISIBLE (-2000 1500);
FORCEPROP 1 LAST PATH I228
J 2
(-1673 1625);
DISPLAY 0.872340 (-1673 1625);
PAINT GREEN (-1673 1625);
DISPLAY INVISIBLE (-1673 1625);
FORCEADD Q_CAP_DIFFBUS..2
R 2
(-950 225);
FORCEPROP 1 LAST PART_NUMBER SP_CH4221MEE01
J 2
(-1066 313);
DISPLAY 0.574468 (-1066 313);
PAINT GREEN (-1066 313);
DISPLAY INVISIBLE (-1066 313);
FORCEPROP 2 LAST VALUE DIFF BUS_0.22UF
J 2
(-1100 225);
DISPLAY 0.553191 (-1100 225);
FORCEPROP 1 LAST $LOCATION C740
J 2
(-716 242);
DISPLAY 0.723404 (-716 242);
PAINT GREEN (-716 242);
FORCEPROP 2 LASTPIN (-875 225) $PN 1
J 0
(-865 235);
DISPLAY 0.808511 (-865 235);
FORCEPROP 2 LASTPIN (-1025 225) $PN 2
J 2
(-1035 235);
DISPLAY 0.808511 (-1035 235);
FORCEPROP 1 LAST PIN_NAMES_ROTATE TRUE
J 2
(-950 225);
DISPLAY 0.489362 (-950 225);
PAINT GREEN (-950 225);
DISPLAY INVISIBLE (-950 225);
FORCEPROP 2 LAST CDS_LIB pure_quanta
J 2
(-950 225);
DISPLAY INVISIBLE (-950 225);
FORCEPROP 1 LAST CDS_LMAN_SYM_OUTLINE -25,50,25,-50
J 2
(-950 225);
DISPLAY 0.468085 (-950 225);
PAINT GREEN (-950 225);
DISPLAY INVISIBLE (-950 225);
FORCEPROP 2 LAST VOLTAGE 6.3V
J 2
(-1300 275);
DISPLAY 0.553191 (-1300 275);
DISPLAY INVISIBLE (-1300 275);
FORCEPROP 1 LAST MATERIAL X6S
J 2
(-941 304);
DISPLAY 0.574468 (-941 304);
PAINT GREEN (-941 304);
DISPLAY INVISIBLE (-941 304);
FORCEPROP 2 LAST PACK_TYPE C0201
J 2
(-1125 275);
DISPLAY 0.553191 (-1125 275);
DISPLAY INVISIBLE (-1125 275);
FORCEPROP 2 LAST TOLERANCE 20%
J 2
(-1025 275);
DISPLAY 0.553191 (-1025 275);
DISPLAY INVISIBLE (-1025 275);
FORCEPROP 1 LAST PATH I229
J 2
(-950 225);
DISPLAY 0.723404 (-950 225);
DISPLAY INVISIBLE (-950 225);
FORCEPROP 1 LAST $LOCATION C740
J 0
(-700 300);
DISPLAY 1.021277 (-700 300);
DISPLAY INVISIBLE (-700 300);
FORCEPROP 2 LAST CDS_LOCATION C740
J 0
(-700 300);
DISPLAY 1.021277 (-700 300);
DISPLAY INVISIBLE (-700 300);
FORCEPROP 2 LAST $SEC 1
J 2
(-775 300);
DISPLAY 0.680851 (-775 300);
PAINT MONO (-775 300);
DISPLAY INVISIBLE (-775 300);
FORCEPROP 2 LAST CDS_SEC 1
J 2
(-775 300);
DISPLAY 0.680851 (-775 300);
DISPLAY INVISIBLE (-775 300);
FORCEADD Q_CAP_DIFFBUS..2
R 2
(-950 175);
FORCEPROP 1 LAST PART_NUMBER SP_CH4221MEE01
J 2
(-1066 263);
DISPLAY 0.574468 (-1066 263);
PAINT GREEN (-1066 263);
DISPLAY INVISIBLE (-1066 263);
FORCEPROP 2 LAST VALUE DIFF BUS_0.22UF
J 2
(-1100 175);
DISPLAY 0.553191 (-1100 175);
FORCEPROP 1 LAST $LOCATION C741
J 2
(-716 192);
DISPLAY 0.723404 (-716 192);
PAINT GREEN (-716 192);
FORCEPROP 2 LASTPIN (-875 175) $PN 1
J 0
(-865 185);
DISPLAY 0.808511 (-865 185);
FORCEPROP 2 LASTPIN (-1025 175) $PN 2
J 2
(-1035 185);
DISPLAY 0.808511 (-1035 185);
FORCEPROP 1 LAST PIN_NAMES_ROTATE TRUE
J 2
(-950 175);
DISPLAY 0.489362 (-950 175);
PAINT GREEN (-950 175);
DISPLAY INVISIBLE (-950 175);
FORCEPROP 2 LAST CDS_LIB pure_quanta
J 2
(-950 175);
DISPLAY INVISIBLE (-950 175);
FORCEPROP 1 LAST CDS_LMAN_SYM_OUTLINE -25,50,25,-50
J 2
(-950 175);
DISPLAY 0.468085 (-950 175);
PAINT GREEN (-950 175);
DISPLAY INVISIBLE (-950 175);
FORCEPROP 2 LAST VOLTAGE 6.3V
J 2
(-1300 225);
DISPLAY 0.553191 (-1300 225);
DISPLAY INVISIBLE (-1300 225);
FORCEPROP 1 LAST MATERIAL X6S
J 2
(-941 254);
DISPLAY 0.574468 (-941 254);
PAINT GREEN (-941 254);
DISPLAY INVISIBLE (-941 254);
FORCEPROP 2 LAST PACK_TYPE C0201
J 2
(-1125 225);
DISPLAY 0.553191 (-1125 225);
DISPLAY INVISIBLE (-1125 225);
FORCEPROP 2 LAST TOLERANCE 20%
J 2
(-1025 225);
DISPLAY 0.553191 (-1025 225);
DISPLAY INVISIBLE (-1025 225);
FORCEPROP 1 LAST PATH I230
J 2
(-950 175);
DISPLAY 0.723404 (-950 175);
DISPLAY INVISIBLE (-950 175);
FORCEPROP 1 LAST $LOCATION C741
J 0
(-700 250);
DISPLAY 1.021277 (-700 250);
DISPLAY INVISIBLE (-700 250);
FORCEPROP 2 LAST CDS_LOCATION C741
J 0
(-700 250);
DISPLAY 1.021277 (-700 250);
DISPLAY INVISIBLE (-700 250);
FORCEPROP 2 LAST $SEC 1
J 2
(-775 250);
DISPLAY 0.680851 (-775 250);
PAINT MONO (-775 250);
DISPLAY INVISIBLE (-775 250);
FORCEPROP 2 LAST CDS_SEC 1
J 2
(-775 250);
DISPLAY 0.680851 (-775 250);
DISPLAY INVISIBLE (-775 250);
FORCEADD Q_CAP_DIFFBUS..2
R 2
(-950 375);
FORCEPROP 1 LAST PART_NUMBER SP_CH4221MEE01
J 2
(-1066 463);
DISPLAY 0.574468 (-1066 463);
PAINT GREEN (-1066 463);
DISPLAY INVISIBLE (-1066 463);
FORCEPROP 2 LAST VALUE DIFF BUS_0.22UF
J 2
(-1100 375);
DISPLAY 0.553191 (-1100 375);
FORCEPROP 1 LAST $LOCATION C739
J 2
(-716 392);
DISPLAY 0.723404 (-716 392);
PAINT GREEN (-716 392);
FORCEPROP 2 LASTPIN (-875 375) $PN 1
J 0
(-865 385);
DISPLAY 0.808511 (-865 385);
FORCEPROP 2 LASTPIN (-1025 375) $PN 2
J 2
(-1035 385);
DISPLAY 0.808511 (-1035 385);
FORCEPROP 1 LAST PIN_NAMES_ROTATE TRUE
J 2
(-950 375);
DISPLAY 0.489362 (-950 375);
PAINT GREEN (-950 375);
DISPLAY INVISIBLE (-950 375);
FORCEPROP 2 LAST CDS_LIB pure_quanta
J 2
(-950 375);
DISPLAY INVISIBLE (-950 375);
FORCEPROP 1 LAST CDS_LMAN_SYM_OUTLINE -25,50,25,-50
J 2
(-950 375);
DISPLAY 0.468085 (-950 375);
PAINT GREEN (-950 375);
DISPLAY INVISIBLE (-950 375);
FORCEPROP 2 LAST VOLTAGE 6.3V
J 2
(-1300 425);
DISPLAY 0.553191 (-1300 425);
DISPLAY INVISIBLE (-1300 425);
FORCEPROP 1 LAST MATERIAL X6S
J 2
(-941 454);
DISPLAY 0.574468 (-941 454);
PAINT GREEN (-941 454);
DISPLAY INVISIBLE (-941 454);
FORCEPROP 2 LAST PACK_TYPE C0201
J 2
(-1125 425);
DISPLAY 0.553191 (-1125 425);
DISPLAY INVISIBLE (-1125 425);
FORCEPROP 2 LAST TOLERANCE 20%
J 2
(-1025 425);
DISPLAY 0.553191 (-1025 425);
DISPLAY INVISIBLE (-1025 425);
FORCEPROP 1 LAST PATH I231
J 2
(-950 375);
DISPLAY 0.723404 (-950 375);
DISPLAY INVISIBLE (-950 375);
FORCEPROP 1 LAST $LOCATION C739
J 0
(-700 450);
DISPLAY 1.021277 (-700 450);
DISPLAY INVISIBLE (-700 450);
FORCEPROP 2 LAST CDS_LOCATION C739
J 0
(-700 450);
DISPLAY 1.021277 (-700 450);
DISPLAY INVISIBLE (-700 450);
FORCEPROP 2 LAST $SEC 1
J 2
(-775 450);
DISPLAY 0.680851 (-775 450);
PAINT MONO (-775 450);
DISPLAY INVISIBLE (-775 450);
FORCEPROP 2 LAST CDS_SEC 1
J 2
(-775 450);
DISPLAY 0.680851 (-775 450);
DISPLAY INVISIBLE (-775 450);
FORCEADD Q_CAP_DIFFBUS..2
R 2
(-950 425);
FORCEPROP 1 LAST PART_NUMBER SP_CH4221MEE01
J 2
(-1066 513);
DISPLAY 0.574468 (-1066 513);
PAINT GREEN (-1066 513);
DISPLAY INVISIBLE (-1066 513);
FORCEPROP 2 LAST VALUE DIFF BUS_0.22UF
J 2
(-1100 425);
DISPLAY 0.553191 (-1100 425);
FORCEPROP 1 LAST $LOCATION C738
J 2
(-716 442);
DISPLAY 0.723404 (-716 442);
PAINT GREEN (-716 442);
FORCEPROP 2 LASTPIN (-875 425) $PN 1
J 0
(-865 435);
DISPLAY 0.808511 (-865 435);
FORCEPROP 2 LASTPIN (-1025 425) $PN 2
J 2
(-1035 435);
DISPLAY 0.808511 (-1035 435);
FORCEPROP 1 LAST PIN_NAMES_ROTATE TRUE
J 2
(-950 425);
DISPLAY 0.489362 (-950 425);
PAINT GREEN (-950 425);
DISPLAY INVISIBLE (-950 425);
FORCEPROP 1 LAST CDS_LMAN_SYM_OUTLINE -25,50,25,-50
J 2
(-950 425);
DISPLAY 0.468085 (-950 425);
PAINT GREEN (-950 425);
DISPLAY INVISIBLE (-950 425);
FORCEPROP 2 LAST CDS_LIB pure_quanta
J 2
(-950 425);
DISPLAY INVISIBLE (-950 425);
FORCEPROP 2 LAST VOLTAGE 6.3V
J 2
(-1300 475);
DISPLAY 0.553191 (-1300 475);
DISPLAY INVISIBLE (-1300 475);
FORCEPROP 1 LAST MATERIAL X6S
J 2
(-941 504);
DISPLAY 0.574468 (-941 504);
PAINT GREEN (-941 504);
DISPLAY INVISIBLE (-941 504);
FORCEPROP 2 LAST PACK_TYPE C0201
J 2
(-1125 475);
DISPLAY 0.553191 (-1125 475);
DISPLAY INVISIBLE (-1125 475);
FORCEPROP 2 LAST TOLERANCE 20%
J 2
(-1025 475);
DISPLAY 0.553191 (-1025 475);
DISPLAY INVISIBLE (-1025 475);
FORCEPROP 1 LAST PATH I232
J 2
(-950 425);
DISPLAY 0.723404 (-950 425);
DISPLAY INVISIBLE (-950 425);
FORCEPROP 1 LAST $LOCATION C738
J 0
(-700 500);
DISPLAY 1.021277 (-700 500);
DISPLAY INVISIBLE (-700 500);
FORCEPROP 2 LAST CDS_LOCATION C738
J 0
(-700 500);
DISPLAY 1.021277 (-700 500);
DISPLAY INVISIBLE (-700 500);
FORCEPROP 2 LAST $SEC 1
J 2
(-775 500);
DISPLAY 0.680851 (-775 500);
PAINT MONO (-775 500);
DISPLAY INVISIBLE (-775 500);
FORCEPROP 2 LAST CDS_SEC 1
J 2
(-775 500);
DISPLAY 0.680851 (-775 500);
DISPLAY INVISIBLE (-775 500);
FORCEADD Q_CAP_DIFFBUS..2
R 2
(-950 575);
FORCEPROP 1 LAST PART_NUMBER SP_CH4221MEE01
J 2
(-1066 663);
DISPLAY 0.574468 (-1066 663);
PAINT GREEN (-1066 663);
DISPLAY INVISIBLE (-1066 663);
FORCEPROP 2 LAST VALUE DIFF BUS_0.22UF
J 2
(-1100 575);
DISPLAY 0.553191 (-1100 575);
FORCEPROP 1 LAST $LOCATION C737
J 2
(-716 592);
DISPLAY 0.723404 (-716 592);
PAINT GREEN (-716 592);
FORCEPROP 2 LASTPIN (-875 575) $PN 1
J 0
(-865 585);
DISPLAY 0.808511 (-865 585);
FORCEPROP 2 LASTPIN (-1025 575) $PN 2
J 2
(-1035 585);
DISPLAY 0.808511 (-1035 585);
FORCEPROP 1 LAST PIN_NAMES_ROTATE TRUE
J 2
(-950 575);
DISPLAY 0.489362 (-950 575);
PAINT GREEN (-950 575);
DISPLAY INVISIBLE (-950 575);
FORCEPROP 2 LAST CDS_LIB pure_quanta
J 2
(-950 575);
DISPLAY INVISIBLE (-950 575);
FORCEPROP 1 LAST CDS_LMAN_SYM_OUTLINE -25,50,25,-50
J 2
(-950 575);
DISPLAY 0.468085 (-950 575);
PAINT GREEN (-950 575);
DISPLAY INVISIBLE (-950 575);
FORCEPROP 2 LAST VOLTAGE 6.3V
J 2
(-1300 625);
DISPLAY 0.553191 (-1300 625);
DISPLAY INVISIBLE (-1300 625);
FORCEPROP 1 LAST MATERIAL X6S
J 2
(-941 654);
DISPLAY 0.574468 (-941 654);
PAINT GREEN (-941 654);
DISPLAY INVISIBLE (-941 654);
FORCEPROP 2 LAST PACK_TYPE C0201
J 2
(-1125 625);
DISPLAY 0.553191 (-1125 625);
DISPLAY INVISIBLE (-1125 625);
FORCEPROP 2 LAST TOLERANCE 20%
J 2
(-1025 625);
DISPLAY 0.553191 (-1025 625);
DISPLAY INVISIBLE (-1025 625);
FORCEPROP 1 LAST PATH I233
J 2
(-950 575);
DISPLAY 0.723404 (-950 575);
DISPLAY INVISIBLE (-950 575);
FORCEPROP 1 LAST $LOCATION C737
J 0
(-700 650);
DISPLAY 1.021277 (-700 650);
DISPLAY INVISIBLE (-700 650);
FORCEPROP 2 LAST CDS_LOCATION C737
J 0
(-700 650);
DISPLAY 1.021277 (-700 650);
DISPLAY INVISIBLE (-700 650);
FORCEPROP 2 LAST $SEC 1
J 2
(-775 650);
DISPLAY 0.680851 (-775 650);
PAINT MONO (-775 650);
DISPLAY INVISIBLE (-775 650);
FORCEPROP 2 LAST CDS_SEC 1
J 2
(-775 650);
DISPLAY 0.680851 (-775 650);
DISPLAY INVISIBLE (-775 650);
FORCEADD Q_CAP_DIFFBUS..2
R 2
(-950 625);
FORCEPROP 1 LAST PART_NUMBER SP_CH4221MEE01
J 2
(-1066 713);
DISPLAY 0.574468 (-1066 713);
PAINT GREEN (-1066 713);
DISPLAY INVISIBLE (-1066 713);
FORCEPROP 2 LAST VALUE DIFF BUS_0.22UF
J 2
(-1100 625);
DISPLAY 0.553191 (-1100 625);
FORCEPROP 1 LAST $LOCATION C736
J 2
(-716 642);
DISPLAY 0.723404 (-716 642);
PAINT GREEN (-716 642);
FORCEPROP 2 LASTPIN (-875 625) $PN 1
J 0
(-865 635);
DISPLAY 0.808511 (-865 635);
FORCEPROP 2 LASTPIN (-1025 625) $PN 2
J 2
(-1035 635);
DISPLAY 0.808511 (-1035 635);
FORCEPROP 1 LAST PIN_NAMES_ROTATE TRUE
J 2
(-950 625);
DISPLAY 0.489362 (-950 625);
PAINT GREEN (-950 625);
DISPLAY INVISIBLE (-950 625);
FORCEPROP 2 LAST CDS_LIB pure_quanta
J 2
(-950 625);
DISPLAY INVISIBLE (-950 625);
FORCEPROP 1 LAST CDS_LMAN_SYM_OUTLINE -25,50,25,-50
J 2
(-950 625);
DISPLAY 0.468085 (-950 625);
PAINT GREEN (-950 625);
DISPLAY INVISIBLE (-950 625);
FORCEPROP 2 LAST VOLTAGE 6.3V
J 2
(-1300 675);
DISPLAY 0.553191 (-1300 675);
DISPLAY INVISIBLE (-1300 675);
FORCEPROP 1 LAST MATERIAL X6S
J 2
(-941 704);
DISPLAY 0.574468 (-941 704);
PAINT GREEN (-941 704);
DISPLAY INVISIBLE (-941 704);
FORCEPROP 2 LAST PACK_TYPE C0201
J 2
(-1125 675);
DISPLAY 0.553191 (-1125 675);
DISPLAY INVISIBLE (-1125 675);
FORCEPROP 2 LAST TOLERANCE 20%
J 2
(-1025 675);
DISPLAY 0.553191 (-1025 675);
DISPLAY INVISIBLE (-1025 675);
FORCEPROP 1 LAST PATH I234
J 2
(-950 625);
DISPLAY 0.723404 (-950 625);
DISPLAY INVISIBLE (-950 625);
FORCEPROP 1 LAST $LOCATION C736
J 0
(-700 700);
DISPLAY 1.021277 (-700 700);
DISPLAY INVISIBLE (-700 700);
FORCEPROP 2 LAST CDS_LOCATION C736
J 0
(-700 700);
DISPLAY 1.021277 (-700 700);
DISPLAY INVISIBLE (-700 700);
FORCEPROP 2 LAST $SEC 1
J 2
(-775 700);
DISPLAY 0.680851 (-775 700);
PAINT MONO (-775 700);
DISPLAY INVISIBLE (-775 700);
FORCEPROP 2 LAST CDS_SEC 1
J 2
(-775 700);
DISPLAY 0.680851 (-775 700);
DISPLAY INVISIBLE (-775 700);
FORCEADD Q_CAP_DIFFBUS..2
R 2
(-950 825);
FORCEPROP 1 LAST PART_NUMBER SP_CH4221MEE01
J 2
(-1066 913);
DISPLAY 0.574468 (-1066 913);
PAINT GREEN (-1066 913);
DISPLAY INVISIBLE (-1066 913);
FORCEPROP 2 LAST VALUE DIFF BUS_0.22UF
J 2
(-1100 825);
DISPLAY 0.553191 (-1100 825);
FORCEPROP 1 LAST $LOCATION C734
J 2
(-716 842);
DISPLAY 0.723404 (-716 842);
PAINT GREEN (-716 842);
FORCEPROP 2 LASTPIN (-875 825) $PN 1
J 0
(-865 835);
DISPLAY 0.808511 (-865 835);
FORCEPROP 2 LASTPIN (-1025 825) $PN 2
J 2
(-1035 835);
DISPLAY 0.808511 (-1035 835);
FORCEPROP 1 LAST PIN_NAMES_ROTATE TRUE
J 2
(-950 825);
DISPLAY 0.489362 (-950 825);
PAINT GREEN (-950 825);
DISPLAY INVISIBLE (-950 825);
FORCEPROP 1 LAST CDS_LMAN_SYM_OUTLINE -25,50,25,-50
J 2
(-950 825);
DISPLAY 0.468085 (-950 825);
PAINT GREEN (-950 825);
DISPLAY INVISIBLE (-950 825);
FORCEPROP 2 LAST CDS_LIB pure_quanta
J 2
(-950 825);
DISPLAY INVISIBLE (-950 825);
FORCEPROP 2 LAST VOLTAGE 6.3V
J 2
(-1300 875);
DISPLAY 0.553191 (-1300 875);
DISPLAY INVISIBLE (-1300 875);
FORCEPROP 1 LAST MATERIAL X6S
J 2
(-941 904);
DISPLAY 0.574468 (-941 904);
PAINT GREEN (-941 904);
DISPLAY INVISIBLE (-941 904);
FORCEPROP 2 LAST PACK_TYPE C0201
J 2
(-1125 875);
DISPLAY 0.553191 (-1125 875);
DISPLAY INVISIBLE (-1125 875);
FORCEPROP 2 LAST TOLERANCE 20%
J 2
(-1025 875);
DISPLAY 0.553191 (-1025 875);
DISPLAY INVISIBLE (-1025 875);
FORCEPROP 1 LAST PATH I235
J 2
(-950 825);
DISPLAY 0.723404 (-950 825);
DISPLAY INVISIBLE (-950 825);
FORCEPROP 1 LAST $LOCATION C734
J 0
(-700 900);
DISPLAY 1.021277 (-700 900);
DISPLAY INVISIBLE (-700 900);
FORCEPROP 2 LAST CDS_LOCATION C734
J 0
(-700 900);
DISPLAY 1.021277 (-700 900);
DISPLAY INVISIBLE (-700 900);
FORCEPROP 2 LAST $SEC 1
J 2
(-775 900);
DISPLAY 0.680851 (-775 900);
PAINT MONO (-775 900);
DISPLAY INVISIBLE (-775 900);
FORCEPROP 2 LAST CDS_SEC 1
J 2
(-775 900);
DISPLAY 0.680851 (-775 900);
DISPLAY INVISIBLE (-775 900);
FORCEADD Q_CAP_DIFFBUS..2
R 2
(-950 775);
FORCEPROP 1 LAST PART_NUMBER SP_CH4221MEE01
J 2
(-1066 863);
DISPLAY 0.574468 (-1066 863);
PAINT GREEN (-1066 863);
DISPLAY INVISIBLE (-1066 863);
FORCEPROP 2 LAST VALUE DIFF BUS_0.22UF
J 2
(-1100 775);
DISPLAY 0.553191 (-1100 775);
FORCEPROP 1 LAST $LOCATION C735
J 2
(-716 792);
DISPLAY 0.723404 (-716 792);
PAINT GREEN (-716 792);
FORCEPROP 2 LASTPIN (-875 775) $PN 1
J 0
(-865 785);
DISPLAY 0.808511 (-865 785);
FORCEPROP 2 LASTPIN (-1025 775) $PN 2
J 2
(-1035 785);
DISPLAY 0.808511 (-1035 785);
FORCEPROP 1 LAST PIN_NAMES_ROTATE TRUE
J 2
(-950 775);
DISPLAY 0.489362 (-950 775);
PAINT GREEN (-950 775);
DISPLAY INVISIBLE (-950 775);
FORCEPROP 1 LAST CDS_LMAN_SYM_OUTLINE -25,50,25,-50
J 2
(-950 775);
DISPLAY 0.468085 (-950 775);
PAINT GREEN (-950 775);
DISPLAY INVISIBLE (-950 775);
FORCEPROP 2 LAST CDS_LIB pure_quanta
J 2
(-950 775);
DISPLAY INVISIBLE (-950 775);
FORCEPROP 2 LAST VOLTAGE 6.3V
J 2
(-1300 825);
DISPLAY 0.553191 (-1300 825);
DISPLAY INVISIBLE (-1300 825);
FORCEPROP 1 LAST MATERIAL X6S
J 2
(-941 854);
DISPLAY 0.574468 (-941 854);
PAINT GREEN (-941 854);
DISPLAY INVISIBLE (-941 854);
FORCEPROP 2 LAST PACK_TYPE C0201
J 2
(-1125 825);
DISPLAY 0.553191 (-1125 825);
DISPLAY INVISIBLE (-1125 825);
FORCEPROP 2 LAST TOLERANCE 20%
J 2
(-1025 825);
DISPLAY 0.553191 (-1025 825);
DISPLAY INVISIBLE (-1025 825);
FORCEPROP 1 LAST PATH I236
J 2
(-950 775);
DISPLAY 0.723404 (-950 775);
DISPLAY INVISIBLE (-950 775);
FORCEPROP 1 LAST $LOCATION C735
J 0
(-700 850);
DISPLAY 1.021277 (-700 850);
DISPLAY INVISIBLE (-700 850);
FORCEPROP 2 LAST CDS_LOCATION C735
J 0
(-700 850);
DISPLAY 1.021277 (-700 850);
DISPLAY INVISIBLE (-700 850);
FORCEPROP 2 LAST $SEC 1
J 2
(-775 850);
DISPLAY 0.680851 (-775 850);
PAINT MONO (-775 850);
DISPLAY INVISIBLE (-775 850);
FORCEPROP 2 LAST CDS_SEC 1
J 2
(-775 850);
DISPLAY 0.680851 (-775 850);
DISPLAY INVISIBLE (-775 850);
FORCEADD Q_CAP_DIFFBUS..2
R 2
(-950 975);
FORCEPROP 1 LAST PART_NUMBER SP_CH4221MEE01
J 2
(-1066 1063);
DISPLAY 0.574468 (-1066 1063);
PAINT GREEN (-1066 1063);
DISPLAY INVISIBLE (-1066 1063);
FORCEPROP 2 LAST VALUE DIFF BUS_0.22UF
J 2
(-1100 975);
DISPLAY 0.553191 (-1100 975);
FORCEPROP 1 LAST $LOCATION C733
J 2
(-716 992);
DISPLAY 0.723404 (-716 992);
PAINT GREEN (-716 992);
FORCEPROP 2 LASTPIN (-875 975) $PN 1
J 0
(-865 985);
DISPLAY 0.808511 (-865 985);
FORCEPROP 2 LASTPIN (-1025 975) $PN 2
J 2
(-1035 985);
DISPLAY 0.808511 (-1035 985);
FORCEPROP 1 LAST PIN_NAMES_ROTATE TRUE
J 2
(-950 975);
DISPLAY 0.489362 (-950 975);
PAINT GREEN (-950 975);
DISPLAY INVISIBLE (-950 975);
FORCEPROP 2 LAST CDS_LIB pure_quanta
J 2
(-950 975);
DISPLAY INVISIBLE (-950 975);
FORCEPROP 1 LAST CDS_LMAN_SYM_OUTLINE -25,50,25,-50
J 2
(-950 975);
DISPLAY 0.468085 (-950 975);
PAINT GREEN (-950 975);
DISPLAY INVISIBLE (-950 975);
FORCEPROP 2 LAST VOLTAGE 6.3V
J 2
(-1300 1025);
DISPLAY 0.553191 (-1300 1025);
DISPLAY INVISIBLE (-1300 1025);
FORCEPROP 1 LAST MATERIAL X6S
J 2
(-941 1054);
DISPLAY 0.574468 (-941 1054);
PAINT GREEN (-941 1054);
DISPLAY INVISIBLE (-941 1054);
FORCEPROP 2 LAST PACK_TYPE C0201
J 2
(-1125 1025);
DISPLAY 0.553191 (-1125 1025);
DISPLAY INVISIBLE (-1125 1025);
FORCEPROP 2 LAST TOLERANCE 20%
J 2
(-1025 1025);
DISPLAY 0.553191 (-1025 1025);
DISPLAY INVISIBLE (-1025 1025);
FORCEPROP 1 LAST PATH I237
J 2
(-950 975);
DISPLAY 0.723404 (-950 975);
DISPLAY INVISIBLE (-950 975);
FORCEPROP 1 LAST $LOCATION C733
J 0
(-700 1050);
DISPLAY 1.021277 (-700 1050);
DISPLAY INVISIBLE (-700 1050);
FORCEPROP 2 LAST CDS_LOCATION C733
J 0
(-700 1050);
DISPLAY 1.021277 (-700 1050);
DISPLAY INVISIBLE (-700 1050);
FORCEPROP 2 LAST $SEC 1
J 2
(-775 1050);
DISPLAY 0.680851 (-775 1050);
PAINT MONO (-775 1050);
DISPLAY INVISIBLE (-775 1050);
FORCEPROP 2 LAST CDS_SEC 1
J 2
(-775 1050);
DISPLAY 0.680851 (-775 1050);
DISPLAY INVISIBLE (-775 1050);
FORCEADD TAP..1
(-400 225);
FORCEPROP 3 LASTPIN (-450 225) SIG_NAME P5E_CPU1_PE0_TX_C_DN<0>
J 0
(-440 235);
DISPLAY 0.659574 (-440 235);
PAINT MONO (-440 235);
DISPLAY INVISIBLE (-440 235);
FORCEPROP 1 LASTPIN (-450 225) BN 0
J 0
(-462 233);
DISPLAY 0.680851 (-462 233);
PAINT GREEN (-462 233);
FORCEPROP 2 LAST CDS_LIB standard
J 0
(-400 225);
DISPLAY INVISIBLE (-400 225);
FORCEPROP 1 LAST BODY_TYPE PLUMBING
J 0
(-400 275);
DISPLAY 0.872340 (-400 275);
PAINT GREEN (-400 275);
DISPLAY INVISIBLE (-400 275);
FORCEPROP 1 LAST HDL_TAP TRUE
J 0
(-75 100);
DISPLAY 0.872340 (-75 100);
DISPLAY INVISIBLE (-75 100);
FORCEPROP 1 LAST PATH I238
J 0
(-402 225);
DISPLAY 0.872340 (-402 225);
PAINT GREEN (-402 225);
DISPLAY INVISIBLE (-402 225);
FORCEADD TAP..1
(-400 425);
FORCEPROP 3 LASTPIN (-450 425) SIG_NAME P5E_CPU1_PE0_TX_C_DN<1>
J 0
(-440 435);
DISPLAY 0.659574 (-440 435);
PAINT MONO (-440 435);
DISPLAY INVISIBLE (-440 435);
FORCEPROP 1 LASTPIN (-450 425) BN 1
J 0
(-462 433);
DISPLAY 0.680851 (-462 433);
PAINT GREEN (-462 433);
FORCEPROP 2 LAST CDS_LIB standard
J 0
(-400 425);
DISPLAY INVISIBLE (-400 425);
FORCEPROP 1 LAST BODY_TYPE PLUMBING
J 0
(-400 475);
DISPLAY 0.872340 (-400 475);
PAINT GREEN (-400 475);
DISPLAY INVISIBLE (-400 475);
FORCEPROP 1 LAST HDL_TAP TRUE
J 0
(-75 300);
DISPLAY 0.872340 (-75 300);
DISPLAY INVISIBLE (-75 300);
FORCEPROP 1 LAST PATH I239
J 0
(-402 425);
DISPLAY 0.872340 (-402 425);
PAINT GREEN (-402 425);
DISPLAY INVISIBLE (-402 425);
FORCEADD TAP..1
(-200 175);
FORCEPROP 3 LASTPIN (-250 175) SIG_NAME P5E_CPU1_PE0_TX_C_DP<0>
J 0
(-240 185);
DISPLAY 0.659574 (-240 185);
PAINT MONO (-240 185);
DISPLAY INVISIBLE (-240 185);
FORCEPROP 1 LASTPIN (-250 175) BN 0
J 0
(-262 183);
DISPLAY 0.680851 (-262 183);
PAINT GREEN (-262 183);
FORCEPROP 2 LAST CDS_LIB standard
J 0
(-200 175);
DISPLAY INVISIBLE (-200 175);
FORCEPROP 1 LAST BODY_TYPE PLUMBING
J 0
(-200 225);
DISPLAY 0.872340 (-200 225);
PAINT GREEN (-200 225);
DISPLAY INVISIBLE (-200 225);
FORCEPROP 1 LAST HDL_TAP TRUE
J 0
(125 50);
DISPLAY 0.872340 (125 50);
DISPLAY INVISIBLE (125 50);
FORCEPROP 1 LAST PATH I240
J 0
(-202 175);
DISPLAY 0.872340 (-202 175);
PAINT GREEN (-202 175);
DISPLAY INVISIBLE (-202 175);
FORCEADD TAP..1
(-200 375);
FORCEPROP 3 LASTPIN (-250 375) SIG_NAME P5E_CPU1_PE0_TX_C_DP<1>
J 0
(-240 385);
DISPLAY 0.659574 (-240 385);
PAINT MONO (-240 385);
DISPLAY INVISIBLE (-240 385);
FORCEPROP 1 LASTPIN (-250 375) BN 1
J 0
(-262 383);
DISPLAY 0.680851 (-262 383);
PAINT GREEN (-262 383);
FORCEPROP 2 LAST CDS_LIB standard
J 0
(-200 375);
DISPLAY INVISIBLE (-200 375);
FORCEPROP 1 LAST BODY_TYPE PLUMBING
J 0
(-200 425);
DISPLAY 0.872340 (-200 425);
PAINT GREEN (-200 425);
DISPLAY INVISIBLE (-200 425);
FORCEPROP 1 LAST HDL_TAP TRUE
J 0
(125 250);
DISPLAY 0.872340 (125 250);
DISPLAY INVISIBLE (125 250);
FORCEPROP 1 LAST PATH I241
J 0
(-202 375);
DISPLAY 0.872340 (-202 375);
PAINT GREEN (-202 375);
DISPLAY INVISIBLE (-202 375);
FORCEADD TAP..1
(-400 625);
FORCEPROP 3 LASTPIN (-450 625) SIG_NAME P5E_CPU1_PE0_TX_C_DN<2>
J 0
(-440 635);
DISPLAY 0.659574 (-440 635);
PAINT MONO (-440 635);
DISPLAY INVISIBLE (-440 635);
FORCEPROP 1 LASTPIN (-450 625) BN 2
J 0
(-462 633);
DISPLAY 0.680851 (-462 633);
PAINT GREEN (-462 633);
FORCEPROP 2 LAST CDS_LIB standard
J 0
(-400 625);
DISPLAY INVISIBLE (-400 625);
FORCEPROP 1 LAST BODY_TYPE PLUMBING
J 0
(-400 675);
DISPLAY 0.872340 (-400 675);
PAINT GREEN (-400 675);
DISPLAY INVISIBLE (-400 675);
FORCEPROP 1 LAST HDL_TAP TRUE
J 0
(-75 500);
DISPLAY 0.872340 (-75 500);
DISPLAY INVISIBLE (-75 500);
FORCEPROP 1 LAST PATH I242
J 0
(-402 625);
DISPLAY 0.872340 (-402 625);
PAINT GREEN (-402 625);
DISPLAY INVISIBLE (-402 625);
FORCEADD TAP..1
(-400 825);
FORCEPROP 3 LASTPIN (-450 825) SIG_NAME P5E_CPU1_PE0_TX_C_DN<3>
J 0
(-440 835);
DISPLAY 0.659574 (-440 835);
PAINT MONO (-440 835);
DISPLAY INVISIBLE (-440 835);
FORCEPROP 1 LASTPIN (-450 825) BN 3
J 0
(-462 833);
DISPLAY 0.680851 (-462 833);
PAINT GREEN (-462 833);
FORCEPROP 2 LAST CDS_LIB standard
J 0
(-400 825);
DISPLAY INVISIBLE (-400 825);
FORCEPROP 1 LAST BODY_TYPE PLUMBING
J 0
(-400 875);
DISPLAY 0.872340 (-400 875);
PAINT GREEN (-400 875);
DISPLAY INVISIBLE (-400 875);
FORCEPROP 1 LAST HDL_TAP TRUE
J 0
(-75 700);
DISPLAY 0.872340 (-75 700);
DISPLAY INVISIBLE (-75 700);
FORCEPROP 1 LAST PATH I243
J 0
(-402 825);
DISPLAY 0.872340 (-402 825);
PAINT GREEN (-402 825);
DISPLAY INVISIBLE (-402 825);
FORCEADD TAP..1
(-200 575);
FORCEPROP 3 LASTPIN (-250 575) SIG_NAME P5E_CPU1_PE0_TX_C_DP<2>
J 0
(-240 585);
DISPLAY 0.659574 (-240 585);
PAINT MONO (-240 585);
DISPLAY INVISIBLE (-240 585);
FORCEPROP 1 LASTPIN (-250 575) BN 2
J 0
(-262 583);
DISPLAY 0.680851 (-262 583);
PAINT GREEN (-262 583);
FORCEPROP 2 LAST CDS_LIB standard
J 0
(-200 575);
DISPLAY INVISIBLE (-200 575);
FORCEPROP 1 LAST BODY_TYPE PLUMBING
J 0
(-200 625);
DISPLAY 0.872340 (-200 625);
PAINT GREEN (-200 625);
DISPLAY INVISIBLE (-200 625);
FORCEPROP 1 LAST HDL_TAP TRUE
J 0
(125 450);
DISPLAY 0.872340 (125 450);
DISPLAY INVISIBLE (125 450);
FORCEPROP 1 LAST PATH I244
J 0
(-202 575);
DISPLAY 0.872340 (-202 575);
PAINT GREEN (-202 575);
DISPLAY INVISIBLE (-202 575);
FORCEADD TAP..1
(-200 775);
FORCEPROP 3 LASTPIN (-250 775) SIG_NAME P5E_CPU1_PE0_TX_C_DP<3>
J 0
(-240 785);
DISPLAY 0.659574 (-240 785);
PAINT MONO (-240 785);
DISPLAY INVISIBLE (-240 785);
FORCEPROP 1 LASTPIN (-250 775) BN 3
J 0
(-262 783);
DISPLAY 0.680851 (-262 783);
PAINT GREEN (-262 783);
FORCEPROP 2 LAST CDS_LIB standard
J 0
(-200 775);
DISPLAY INVISIBLE (-200 775);
FORCEPROP 1 LAST BODY_TYPE PLUMBING
J 0
(-200 825);
DISPLAY 0.872340 (-200 825);
PAINT GREEN (-200 825);
DISPLAY INVISIBLE (-200 825);
FORCEPROP 1 LAST HDL_TAP TRUE
J 0
(125 650);
DISPLAY 0.872340 (125 650);
DISPLAY INVISIBLE (125 650);
FORCEPROP 1 LAST PATH I245
J 0
(-202 775);
DISPLAY 0.872340 (-202 775);
PAINT GREEN (-202 775);
DISPLAY INVISIBLE (-202 775);
FORCEADD Q_CAP_DIFFBUS..2
R 2
(-950 1025);
FORCEPROP 1 LAST PART_NUMBER SP_CH4221MEE01
J 2
(-1066 1113);
DISPLAY 0.574468 (-1066 1113);
PAINT GREEN (-1066 1113);
DISPLAY INVISIBLE (-1066 1113);
FORCEPROP 2 LAST VALUE DIFF BUS_0.22UF
J 2
(-1100 1025);
DISPLAY 0.553191 (-1100 1025);
FORCEPROP 1 LAST $LOCATION C732
J 2
(-716 1042);
DISPLAY 0.723404 (-716 1042);
PAINT GREEN (-716 1042);
FORCEPROP 2 LASTPIN (-875 1025) $PN 1
J 0
(-865 1035);
DISPLAY 0.808511 (-865 1035);
FORCEPROP 2 LASTPIN (-1025 1025) $PN 2
J 2
(-1035 1035);
DISPLAY 0.808511 (-1035 1035);
FORCEPROP 1 LAST PIN_NAMES_ROTATE TRUE
J 2
(-950 1025);
DISPLAY 0.489362 (-950 1025);
PAINT GREEN (-950 1025);
DISPLAY INVISIBLE (-950 1025);
FORCEPROP 2 LAST CDS_LIB pure_quanta
J 2
(-950 1025);
DISPLAY INVISIBLE (-950 1025);
FORCEPROP 1 LAST CDS_LMAN_SYM_OUTLINE -25,50,25,-50
J 2
(-950 1025);
DISPLAY 0.468085 (-950 1025);
PAINT GREEN (-950 1025);
DISPLAY INVISIBLE (-950 1025);
FORCEPROP 2 LAST VOLTAGE 6.3V
J 2
(-1300 1075);
DISPLAY 0.553191 (-1300 1075);
DISPLAY INVISIBLE (-1300 1075);
FORCEPROP 1 LAST MATERIAL X6S
J 2
(-941 1104);
DISPLAY 0.574468 (-941 1104);
PAINT GREEN (-941 1104);
DISPLAY INVISIBLE (-941 1104);
FORCEPROP 2 LAST PACK_TYPE C0201
J 2
(-1125 1075);
DISPLAY 0.553191 (-1125 1075);
DISPLAY INVISIBLE (-1125 1075);
FORCEPROP 2 LAST TOLERANCE 20%
J 2
(-1025 1075);
DISPLAY 0.553191 (-1025 1075);
DISPLAY INVISIBLE (-1025 1075);
FORCEPROP 1 LAST PATH I246
J 2
(-950 1025);
DISPLAY 0.723404 (-950 1025);
DISPLAY INVISIBLE (-950 1025);
FORCEPROP 1 LAST $LOCATION C732
J 0
(-700 1100);
DISPLAY 1.021277 (-700 1100);
DISPLAY INVISIBLE (-700 1100);
FORCEPROP 2 LAST CDS_LOCATION C732
J 0
(-700 1100);
DISPLAY 1.021277 (-700 1100);
DISPLAY INVISIBLE (-700 1100);
FORCEPROP 2 LAST $SEC 1
J 2
(-775 1100);
DISPLAY 0.680851 (-775 1100);
PAINT MONO (-775 1100);
DISPLAY INVISIBLE (-775 1100);
FORCEPROP 2 LAST CDS_SEC 1
J 2
(-775 1100);
DISPLAY 0.680851 (-775 1100);
DISPLAY INVISIBLE (-775 1100);
FORCEADD Q_CAP_DIFFBUS..2
R 2
(-950 1175);
FORCEPROP 1 LAST PART_NUMBER SP_CH4221MEE01
J 2
(-1066 1263);
DISPLAY 0.574468 (-1066 1263);
PAINT GREEN (-1066 1263);
DISPLAY INVISIBLE (-1066 1263);
FORCEPROP 2 LAST VALUE DIFF BUS_0.22UF
J 2
(-1100 1175);
DISPLAY 0.553191 (-1100 1175);
FORCEPROP 1 LAST $LOCATION C731
J 2
(-716 1192);
DISPLAY 0.723404 (-716 1192);
PAINT GREEN (-716 1192);
FORCEPROP 2 LASTPIN (-875 1175) $PN 1
J 0
(-865 1185);
DISPLAY 0.808511 (-865 1185);
FORCEPROP 2 LASTPIN (-1025 1175) $PN 2
J 2
(-1035 1185);
DISPLAY 0.808511 (-1035 1185);
FORCEPROP 1 LAST PIN_NAMES_ROTATE TRUE
J 2
(-950 1175);
DISPLAY 0.489362 (-950 1175);
PAINT GREEN (-950 1175);
DISPLAY INVISIBLE (-950 1175);
FORCEPROP 2 LAST CDS_LIB pure_quanta
J 2
(-950 1175);
DISPLAY INVISIBLE (-950 1175);
FORCEPROP 1 LAST CDS_LMAN_SYM_OUTLINE -25,50,25,-50
J 2
(-950 1175);
DISPLAY 0.468085 (-950 1175);
PAINT GREEN (-950 1175);
DISPLAY INVISIBLE (-950 1175);
FORCEPROP 2 LAST VOLTAGE 6.3V
J 2
(-1300 1225);
DISPLAY 0.553191 (-1300 1225);
DISPLAY INVISIBLE (-1300 1225);
FORCEPROP 1 LAST MATERIAL X6S
J 2
(-941 1254);
DISPLAY 0.574468 (-941 1254);
PAINT GREEN (-941 1254);
DISPLAY INVISIBLE (-941 1254);
FORCEPROP 2 LAST PACK_TYPE C0201
J 2
(-1125 1225);
DISPLAY 0.553191 (-1125 1225);
DISPLAY INVISIBLE (-1125 1225);
FORCEPROP 2 LAST TOLERANCE 20%
J 2
(-1025 1225);
DISPLAY 0.553191 (-1025 1225);
DISPLAY INVISIBLE (-1025 1225);
FORCEPROP 1 LAST PATH I247
J 2
(-950 1175);
DISPLAY 0.723404 (-950 1175);
DISPLAY INVISIBLE (-950 1175);
FORCEPROP 1 LAST $LOCATION C731
J 0
(-700 1250);
DISPLAY 1.021277 (-700 1250);
DISPLAY INVISIBLE (-700 1250);
FORCEPROP 2 LAST CDS_LOCATION C731
J 0
(-700 1250);
DISPLAY 1.021277 (-700 1250);
DISPLAY INVISIBLE (-700 1250);
FORCEPROP 2 LAST $SEC 1
J 2
(-775 1250);
DISPLAY 0.680851 (-775 1250);
PAINT MONO (-775 1250);
DISPLAY INVISIBLE (-775 1250);
FORCEPROP 2 LAST CDS_SEC 1
J 2
(-775 1250);
DISPLAY 0.680851 (-775 1250);
DISPLAY INVISIBLE (-775 1250);
FORCEADD Q_CAP_DIFFBUS..2
R 2
(-950 1225);
FORCEPROP 1 LAST PART_NUMBER SP_CH4221MEE01
J 2
(-1066 1313);
DISPLAY 0.574468 (-1066 1313);
PAINT GREEN (-1066 1313);
DISPLAY INVISIBLE (-1066 1313);
FORCEPROP 2 LAST VALUE DIFF BUS_0.22UF
J 2
(-1100 1225);
DISPLAY 0.553191 (-1100 1225);
FORCEPROP 1 LAST $LOCATION C730
J 2
(-716 1242);
DISPLAY 0.723404 (-716 1242);
PAINT GREEN (-716 1242);
FORCEPROP 2 LASTPIN (-875 1225) $PN 1
J 0
(-865 1235);
DISPLAY 0.808511 (-865 1235);
FORCEPROP 2 LASTPIN (-1025 1225) $PN 2
J 2
(-1035 1235);
DISPLAY 0.808511 (-1035 1235);
FORCEPROP 1 LAST PIN_NAMES_ROTATE TRUE
J 2
(-950 1225);
DISPLAY 0.489362 (-950 1225);
PAINT GREEN (-950 1225);
DISPLAY INVISIBLE (-950 1225);
FORCEPROP 2 LAST CDS_LIB pure_quanta
J 2
(-950 1225);
DISPLAY INVISIBLE (-950 1225);
FORCEPROP 1 LAST CDS_LMAN_SYM_OUTLINE -25,50,25,-50
J 2
(-950 1225);
DISPLAY 0.468085 (-950 1225);
PAINT GREEN (-950 1225);
DISPLAY INVISIBLE (-950 1225);
FORCEPROP 2 LAST VOLTAGE 6.3V
J 2
(-1300 1275);
DISPLAY 0.553191 (-1300 1275);
DISPLAY INVISIBLE (-1300 1275);
FORCEPROP 1 LAST MATERIAL X6S
J 2
(-941 1304);
DISPLAY 0.574468 (-941 1304);
PAINT GREEN (-941 1304);
DISPLAY INVISIBLE (-941 1304);
FORCEPROP 2 LAST PACK_TYPE C0201
J 2
(-1125 1275);
DISPLAY 0.553191 (-1125 1275);
DISPLAY INVISIBLE (-1125 1275);
FORCEPROP 2 LAST TOLERANCE 20%
J 2
(-1025 1275);
DISPLAY 0.553191 (-1025 1275);
DISPLAY INVISIBLE (-1025 1275);
FORCEPROP 1 LAST PATH I248
J 2
(-950 1225);
DISPLAY 0.723404 (-950 1225);
DISPLAY INVISIBLE (-950 1225);
FORCEPROP 1 LAST $LOCATION C730
J 0
(-700 1300);
DISPLAY 1.021277 (-700 1300);
DISPLAY INVISIBLE (-700 1300);
FORCEPROP 2 LAST CDS_LOCATION C730
J 0
(-700 1300);
DISPLAY 1.021277 (-700 1300);
DISPLAY INVISIBLE (-700 1300);
FORCEPROP 2 LAST $SEC 1
J 2
(-775 1300);
DISPLAY 0.680851 (-775 1300);
PAINT MONO (-775 1300);
DISPLAY INVISIBLE (-775 1300);
FORCEPROP 2 LAST CDS_SEC 1
J 2
(-775 1300);
DISPLAY 0.680851 (-775 1300);
DISPLAY INVISIBLE (-775 1300);
FORCEADD Q_CAP_DIFFBUS..2
R 2
(-950 1375);
FORCEPROP 1 LAST PART_NUMBER SP_CH4221MEE01
J 2
(-1066 1463);
DISPLAY 0.574468 (-1066 1463);
PAINT GREEN (-1066 1463);
DISPLAY INVISIBLE (-1066 1463);
FORCEPROP 2 LAST VALUE DIFF BUS_0.22UF
J 2
(-1100 1375);
DISPLAY 0.553191 (-1100 1375);
FORCEPROP 1 LAST $LOCATION C729
J 2
(-716 1392);
DISPLAY 0.723404 (-716 1392);
PAINT GREEN (-716 1392);
FORCEPROP 2 LASTPIN (-875 1375) $PN 1
J 0
(-865 1385);
DISPLAY 0.808511 (-865 1385);
FORCEPROP 2 LASTPIN (-1025 1375) $PN 2
J 2
(-1035 1385);
DISPLAY 0.808511 (-1035 1385);
FORCEPROP 1 LAST PIN_NAMES_ROTATE TRUE
J 2
(-950 1375);
DISPLAY 0.489362 (-950 1375);
PAINT GREEN (-950 1375);
DISPLAY INVISIBLE (-950 1375);
FORCEPROP 2 LAST CDS_LIB pure_quanta
J 2
(-950 1375);
DISPLAY INVISIBLE (-950 1375);
FORCEPROP 1 LAST CDS_LMAN_SYM_OUTLINE -25,50,25,-50
J 2
(-950 1375);
DISPLAY 0.468085 (-950 1375);
PAINT GREEN (-950 1375);
DISPLAY INVISIBLE (-950 1375);
FORCEPROP 2 LAST VOLTAGE 6.3V
J 2
(-1300 1425);
DISPLAY 0.553191 (-1300 1425);
DISPLAY INVISIBLE (-1300 1425);
FORCEPROP 1 LAST MATERIAL X6S
J 2
(-941 1454);
DISPLAY 0.574468 (-941 1454);
PAINT GREEN (-941 1454);
DISPLAY INVISIBLE (-941 1454);
FORCEPROP 2 LAST PACK_TYPE C0201
J 2
(-1125 1425);
DISPLAY 0.553191 (-1125 1425);
DISPLAY INVISIBLE (-1125 1425);
FORCEPROP 2 LAST TOLERANCE 20%
J 2
(-1025 1425);
DISPLAY 0.553191 (-1025 1425);
DISPLAY INVISIBLE (-1025 1425);
FORCEPROP 1 LAST PATH I249
J 2
(-950 1375);
DISPLAY 0.723404 (-950 1375);
DISPLAY INVISIBLE (-950 1375);
FORCEPROP 1 LAST $LOCATION C729
J 0
(-700 1450);
DISPLAY 1.021277 (-700 1450);
DISPLAY INVISIBLE (-700 1450);
FORCEPROP 2 LAST CDS_LOCATION C729
J 0
(-700 1450);
DISPLAY 1.021277 (-700 1450);
DISPLAY INVISIBLE (-700 1450);
FORCEPROP 2 LAST $SEC 1
J 2
(-775 1450);
DISPLAY 0.680851 (-775 1450);
PAINT MONO (-775 1450);
DISPLAY INVISIBLE (-775 1450);
FORCEPROP 2 LAST CDS_SEC 1
J 2
(-775 1450);
DISPLAY 0.680851 (-775 1450);
DISPLAY INVISIBLE (-775 1450);
FORCEADD Q_CAP_DIFFBUS..2
R 2
(-950 1425);
FORCEPROP 1 LAST PART_NUMBER SP_CH4221MEE01
J 2
(-1066 1513);
DISPLAY 0.574468 (-1066 1513);
PAINT GREEN (-1066 1513);
DISPLAY INVISIBLE (-1066 1513);
FORCEPROP 2 LAST VALUE DIFF BUS_0.22UF
J 2
(-1100 1425);
DISPLAY 0.553191 (-1100 1425);
FORCEPROP 1 LAST $LOCATION C728
J 2
(-716 1442);
DISPLAY 0.723404 (-716 1442);
PAINT GREEN (-716 1442);
FORCEPROP 2 LASTPIN (-875 1425) $PN 1
J 0
(-865 1435);
DISPLAY 0.808511 (-865 1435);
FORCEPROP 2 LASTPIN (-1025 1425) $PN 2
J 2
(-1035 1435);
DISPLAY 0.808511 (-1035 1435);
FORCEPROP 1 LAST PIN_NAMES_ROTATE TRUE
J 2
(-950 1425);
DISPLAY 0.489362 (-950 1425);
PAINT GREEN (-950 1425);
DISPLAY INVISIBLE (-950 1425);
FORCEPROP 2 LAST CDS_LIB pure_quanta
J 2
(-950 1425);
DISPLAY INVISIBLE (-950 1425);
FORCEPROP 1 LAST CDS_LMAN_SYM_OUTLINE -25,50,25,-50
J 2
(-950 1425);
DISPLAY 0.468085 (-950 1425);
PAINT GREEN (-950 1425);
DISPLAY INVISIBLE (-950 1425);
FORCEPROP 2 LAST VOLTAGE 6.3V
J 2
(-1300 1475);
DISPLAY 0.553191 (-1300 1475);
DISPLAY INVISIBLE (-1300 1475);
FORCEPROP 1 LAST MATERIAL X6S
J 2
(-941 1504);
DISPLAY 0.574468 (-941 1504);
PAINT GREEN (-941 1504);
DISPLAY INVISIBLE (-941 1504);
FORCEPROP 2 LAST PACK_TYPE C0201
J 2
(-1125 1475);
DISPLAY 0.553191 (-1125 1475);
DISPLAY INVISIBLE (-1125 1475);
FORCEPROP 2 LAST TOLERANCE 20%
J 2
(-1025 1475);
DISPLAY 0.553191 (-1025 1475);
DISPLAY INVISIBLE (-1025 1475);
FORCEPROP 1 LAST PATH I250
J 2
(-950 1425);
DISPLAY 0.723404 (-950 1425);
DISPLAY INVISIBLE (-950 1425);
FORCEPROP 1 LAST $LOCATION C728
J 0
(-700 1500);
DISPLAY 1.021277 (-700 1500);
DISPLAY INVISIBLE (-700 1500);
FORCEPROP 2 LAST CDS_LOCATION C728
J 0
(-700 1500);
DISPLAY 1.021277 (-700 1500);
DISPLAY INVISIBLE (-700 1500);
FORCEPROP 2 LAST $SEC 1
J 2
(-775 1500);
DISPLAY 0.680851 (-775 1500);
PAINT MONO (-775 1500);
DISPLAY INVISIBLE (-775 1500);
FORCEPROP 2 LAST CDS_SEC 1
J 2
(-775 1500);
DISPLAY 0.680851 (-775 1500);
DISPLAY INVISIBLE (-775 1500);
FORCEADD Q_CAP_DIFFBUS..2
R 2
(-950 1575);
FORCEPROP 1 LAST PART_NUMBER SP_CH4221MEE01
J 2
(-1066 1663);
DISPLAY 0.574468 (-1066 1663);
PAINT GREEN (-1066 1663);
DISPLAY INVISIBLE (-1066 1663);
FORCEPROP 2 LAST VALUE DIFF BUS_0.22UF
J 2
(-1100 1575);
DISPLAY 0.553191 (-1100 1575);
FORCEPROP 1 LAST $LOCATION C727
J 2
(-716 1592);
DISPLAY 0.723404 (-716 1592);
PAINT GREEN (-716 1592);
FORCEPROP 2 LASTPIN (-875 1575) $PN 1
J 0
(-865 1585);
DISPLAY 0.808511 (-865 1585);
FORCEPROP 2 LASTPIN (-1025 1575) $PN 2
J 2
(-1035 1585);
DISPLAY 0.808511 (-1035 1585);
FORCEPROP 1 LAST PIN_NAMES_ROTATE TRUE
J 2
(-950 1575);
DISPLAY 0.489362 (-950 1575);
PAINT GREEN (-950 1575);
DISPLAY INVISIBLE (-950 1575);
FORCEPROP 2 LAST CDS_LIB pure_quanta
J 2
(-950 1575);
DISPLAY INVISIBLE (-950 1575);
FORCEPROP 1 LAST CDS_LMAN_SYM_OUTLINE -25,50,25,-50
J 2
(-950 1575);
DISPLAY 0.468085 (-950 1575);
PAINT GREEN (-950 1575);
DISPLAY INVISIBLE (-950 1575);
FORCEPROP 2 LAST VOLTAGE 6.3V
J 2
(-1300 1625);
DISPLAY 0.553191 (-1300 1625);
DISPLAY INVISIBLE (-1300 1625);
FORCEPROP 1 LAST MATERIAL X6S
J 2
(-941 1654);
DISPLAY 0.574468 (-941 1654);
PAINT GREEN (-941 1654);
DISPLAY INVISIBLE (-941 1654);
FORCEPROP 2 LAST PACK_TYPE C0201
J 2
(-1125 1625);
DISPLAY 0.553191 (-1125 1625);
DISPLAY INVISIBLE (-1125 1625);
FORCEPROP 2 LAST TOLERANCE 20%
J 2
(-1025 1625);
DISPLAY 0.553191 (-1025 1625);
DISPLAY INVISIBLE (-1025 1625);
FORCEPROP 1 LAST PATH I251
J 2
(-950 1575);
DISPLAY 0.723404 (-950 1575);
DISPLAY INVISIBLE (-950 1575);
FORCEPROP 1 LAST $LOCATION C727
J 0
(-700 1650);
DISPLAY 1.021277 (-700 1650);
DISPLAY INVISIBLE (-700 1650);
FORCEPROP 2 LAST CDS_LOCATION C727
J 0
(-700 1650);
DISPLAY 1.021277 (-700 1650);
DISPLAY INVISIBLE (-700 1650);
FORCEPROP 2 LAST $SEC 1
J 2
(-775 1650);
DISPLAY 0.680851 (-775 1650);
PAINT MONO (-775 1650);
DISPLAY INVISIBLE (-775 1650);
FORCEPROP 2 LAST CDS_SEC 1
J 2
(-775 1650);
DISPLAY 0.680851 (-775 1650);
DISPLAY INVISIBLE (-775 1650);
FORCEADD TAP..1
(-400 1025);
FORCEPROP 3 LASTPIN (-450 1025) SIG_NAME P5E_CPU1_PE0_TX_C_DN<4>
J 0
(-440 1035);
DISPLAY 0.659574 (-440 1035);
PAINT MONO (-440 1035);
DISPLAY INVISIBLE (-440 1035);
FORCEPROP 1 LASTPIN (-450 1025) BN 4
J 0
(-462 1033);
DISPLAY 0.680851 (-462 1033);
PAINT GREEN (-462 1033);
FORCEPROP 2 LAST CDS_LIB standard
J 0
(-400 1025);
DISPLAY INVISIBLE (-400 1025);
FORCEPROP 1 LAST BODY_TYPE PLUMBING
J 0
(-400 1075);
DISPLAY 0.872340 (-400 1075);
PAINT GREEN (-400 1075);
DISPLAY INVISIBLE (-400 1075);
FORCEPROP 1 LAST HDL_TAP TRUE
J 0
(-75 900);
DISPLAY 0.872340 (-75 900);
DISPLAY INVISIBLE (-75 900);
FORCEPROP 1 LAST PATH I252
J 0
(-402 1025);
DISPLAY 0.872340 (-402 1025);
PAINT GREEN (-402 1025);
DISPLAY INVISIBLE (-402 1025);
FORCEADD TAP..1
(-400 1425);
FORCEPROP 3 LASTPIN (-450 1425) SIG_NAME P5E_CPU1_PE0_TX_C_DN<6>
J 0
(-440 1435);
DISPLAY 0.659574 (-440 1435);
PAINT MONO (-440 1435);
DISPLAY INVISIBLE (-440 1435);
FORCEPROP 1 LASTPIN (-450 1425) BN 6
J 0
(-462 1433);
DISPLAY 0.680851 (-462 1433);
PAINT GREEN (-462 1433);
FORCEPROP 2 LAST CDS_LIB standard
J 0
(-400 1425);
DISPLAY INVISIBLE (-400 1425);
FORCEPROP 1 LAST BODY_TYPE PLUMBING
J 0
(-400 1475);
DISPLAY 0.872340 (-400 1475);
PAINT GREEN (-400 1475);
DISPLAY INVISIBLE (-400 1475);
FORCEPROP 1 LAST HDL_TAP TRUE
J 0
(-75 1300);
DISPLAY 0.872340 (-75 1300);
DISPLAY INVISIBLE (-75 1300);
FORCEPROP 1 LAST PATH I253
J 0
(-402 1425);
DISPLAY 0.872340 (-402 1425);
PAINT GREEN (-402 1425);
DISPLAY INVISIBLE (-402 1425);
FORCEADD TAP..1
(-200 1175);
FORCEPROP 3 LASTPIN (-250 1175) SIG_NAME P5E_CPU1_PE0_TX_C_DP<5>
J 0
(-240 1185);
DISPLAY 0.659574 (-240 1185);
PAINT MONO (-240 1185);
DISPLAY INVISIBLE (-240 1185);
FORCEPROP 1 LASTPIN (-250 1175) BN 5
J 0
(-262 1183);
DISPLAY 0.680851 (-262 1183);
PAINT GREEN (-262 1183);
FORCEPROP 2 LAST CDS_LIB standard
J 0
(-200 1175);
DISPLAY INVISIBLE (-200 1175);
FORCEPROP 1 LAST BODY_TYPE PLUMBING
J 0
(-200 1225);
DISPLAY 0.872340 (-200 1225);
PAINT GREEN (-200 1225);
DISPLAY INVISIBLE (-200 1225);
FORCEPROP 1 LAST HDL_TAP TRUE
J 0
(125 1050);
DISPLAY 0.872340 (125 1050);
DISPLAY INVISIBLE (125 1050);
FORCEPROP 1 LAST PATH I254
J 0
(-202 1175);
DISPLAY 0.872340 (-202 1175);
PAINT GREEN (-202 1175);
DISPLAY INVISIBLE (-202 1175);
FORCEADD TAP..1
(-200 1375);
FORCEPROP 3 LASTPIN (-250 1375) SIG_NAME P5E_CPU1_PE0_TX_C_DP<6>
J 0
(-240 1385);
DISPLAY 0.659574 (-240 1385);
PAINT MONO (-240 1385);
DISPLAY INVISIBLE (-240 1385);
FORCEPROP 1 LASTPIN (-250 1375) BN 6
J 0
(-262 1383);
DISPLAY 0.680851 (-262 1383);
PAINT GREEN (-262 1383);
FORCEPROP 2 LAST CDS_LIB standard
J 0
(-200 1375);
DISPLAY INVISIBLE (-200 1375);
FORCEPROP 1 LAST BODY_TYPE PLUMBING
J 0
(-200 1425);
DISPLAY 0.872340 (-200 1425);
PAINT GREEN (-200 1425);
DISPLAY INVISIBLE (-200 1425);
FORCEPROP 1 LAST HDL_TAP TRUE
J 0
(125 1250);
DISPLAY 0.872340 (125 1250);
DISPLAY INVISIBLE (125 1250);
FORCEPROP 1 LAST PATH I255
J 0
(-202 1375);
DISPLAY 0.872340 (-202 1375);
PAINT GREEN (-202 1375);
DISPLAY INVISIBLE (-202 1375);
FORCEADD TAP..1
(-400 1625);
FORCEPROP 3 LASTPIN (-450 1625) SIG_NAME P5E_CPU1_PE0_TX_C_DN<7>
J 0
(-440 1635);
DISPLAY 0.659574 (-440 1635);
PAINT MONO (-440 1635);
DISPLAY INVISIBLE (-440 1635);
FORCEPROP 1 LASTPIN (-450 1625) BN 7
J 0
(-462 1633);
DISPLAY 0.680851 (-462 1633);
PAINT GREEN (-462 1633);
FORCEPROP 2 LAST CDS_LIB standard
J 0
(-400 1625);
DISPLAY INVISIBLE (-400 1625);
FORCEPROP 1 LAST BODY_TYPE PLUMBING
J 0
(-400 1675);
DISPLAY 0.872340 (-400 1675);
PAINT GREEN (-400 1675);
DISPLAY INVISIBLE (-400 1675);
FORCEPROP 1 LAST HDL_TAP TRUE
J 0
(-75 1500);
DISPLAY 0.872340 (-75 1500);
DISPLAY INVISIBLE (-75 1500);
FORCEPROP 1 LAST PATH I256
J 0
(-402 1625);
DISPLAY 0.872340 (-402 1625);
PAINT GREEN (-402 1625);
DISPLAY INVISIBLE (-402 1625);
FORCEADD TAP..1
(-200 1575);
FORCEPROP 3 LASTPIN (-250 1575) SIG_NAME P5E_CPU1_PE0_TX_C_DP<7>
J 0
(-240 1585);
DISPLAY 0.659574 (-240 1585);
PAINT MONO (-240 1585);
DISPLAY INVISIBLE (-240 1585);
FORCEPROP 1 LASTPIN (-250 1575) BN 7
J 0
(-262 1583);
DISPLAY 0.680851 (-262 1583);
PAINT GREEN (-262 1583);
FORCEPROP 2 LAST CDS_LIB standard
J 0
(-200 1575);
DISPLAY INVISIBLE (-200 1575);
FORCEPROP 1 LAST BODY_TYPE PLUMBING
J 0
(-200 1625);
DISPLAY 0.872340 (-200 1625);
PAINT GREEN (-200 1625);
DISPLAY INVISIBLE (-200 1625);
FORCEPROP 1 LAST HDL_TAP TRUE
J 0
(125 1450);
DISPLAY 0.872340 (125 1450);
DISPLAY INVISIBLE (125 1450);
FORCEPROP 1 LAST PATH I257
J 0
(-202 1575);
DISPLAY 0.872340 (-202 1575);
PAINT GREEN (-202 1575);
DISPLAY INVISIBLE (-202 1575);
FORCEADD TAP..1
R 2
(-1925 2150);
FORCEPROP 3 LASTPIN (-1875 2150) SIG_NAME P5E_CPU1_PE0_TX_DP<8>
J 0
(-1865 2160);
DISPLAY 0.659574 (-1865 2160);
PAINT MONO (-1865 2160);
DISPLAY INVISIBLE (-1865 2160);
FORCEPROP 1 LASTPIN (-1875 2150) BN 8
J 2
(-1863 2158);
DISPLAY 0.680851 (-1863 2158);
PAINT GREEN (-1863 2158);
FORCEPROP 2 LAST CDS_LIB standard
J 0
(-1925 2150);
DISPLAY INVISIBLE (-1925 2150);
FORCEPROP 1 LAST BODY_TYPE PLUMBING
J 2
(-1925 2200);
DISPLAY 0.872340 (-1925 2200);
PAINT GREEN (-1925 2200);
DISPLAY INVISIBLE (-1925 2200);
FORCEPROP 1 LAST HDL_TAP TRUE
J 2
(-2250 2025);
DISPLAY 0.872340 (-2250 2025);
DISPLAY INVISIBLE (-2250 2025);
FORCEPROP 1 LAST PATH I258
J 2
(-1923 2150);
DISPLAY 0.872340 (-1923 2150);
PAINT GREEN (-1923 2150);
DISPLAY INVISIBLE (-1923 2150);
FORCEADD TAP..1
R 2
(-1925 2350);
FORCEPROP 3 LASTPIN (-1875 2350) SIG_NAME P5E_CPU1_PE0_TX_DP<9>
J 0
(-1865 2360);
DISPLAY 0.659574 (-1865 2360);
PAINT MONO (-1865 2360);
DISPLAY INVISIBLE (-1865 2360);
FORCEPROP 1 LASTPIN (-1875 2350) BN 9
J 2
(-1863 2358);
DISPLAY 0.680851 (-1863 2358);
PAINT GREEN (-1863 2358);
FORCEPROP 2 LAST CDS_LIB standard
J 0
(-1925 2350);
DISPLAY INVISIBLE (-1925 2350);
FORCEPROP 1 LAST BODY_TYPE PLUMBING
J 2
(-1925 2400);
DISPLAY 0.872340 (-1925 2400);
PAINT GREEN (-1925 2400);
DISPLAY INVISIBLE (-1925 2400);
FORCEPROP 1 LAST HDL_TAP TRUE
J 2
(-2250 2225);
DISPLAY 0.872340 (-2250 2225);
DISPLAY INVISIBLE (-2250 2225);
FORCEPROP 1 LAST PATH I259
J 2
(-1923 2350);
DISPLAY 0.872340 (-1923 2350);
PAINT GREEN (-1923 2350);
DISPLAY INVISIBLE (-1923 2350);
FORCEADD TAP..1
R 2
(-1675 2200);
FORCEPROP 3 LASTPIN (-1625 2200) SIG_NAME P5E_CPU1_PE0_TX_DN<8>
J 0
(-1615 2210);
DISPLAY 0.659574 (-1615 2210);
PAINT MONO (-1615 2210);
DISPLAY INVISIBLE (-1615 2210);
FORCEPROP 1 LASTPIN (-1625 2200) BN 8
J 2
(-1613 2208);
DISPLAY 0.680851 (-1613 2208);
PAINT GREEN (-1613 2208);
FORCEPROP 2 LAST CDS_LIB standard
J 0
(-1675 2200);
DISPLAY INVISIBLE (-1675 2200);
FORCEPROP 1 LAST BODY_TYPE PLUMBING
J 2
(-1675 2250);
DISPLAY 0.872340 (-1675 2250);
PAINT GREEN (-1675 2250);
DISPLAY INVISIBLE (-1675 2250);
FORCEPROP 1 LAST HDL_TAP TRUE
J 2
(-2000 2075);
DISPLAY 0.872340 (-2000 2075);
DISPLAY INVISIBLE (-2000 2075);
FORCEPROP 1 LAST PATH I260
J 2
(-1673 2200);
DISPLAY 0.872340 (-1673 2200);
PAINT GREEN (-1673 2200);
DISPLAY INVISIBLE (-1673 2200);
FORCEADD TAP..1
R 2
(-1675 2400);
FORCEPROP 3 LASTPIN (-1625 2400) SIG_NAME P5E_CPU1_PE0_TX_DN<9>
J 0
(-1615 2410);
DISPLAY 0.659574 (-1615 2410);
PAINT MONO (-1615 2410);
DISPLAY INVISIBLE (-1615 2410);
FORCEPROP 1 LASTPIN (-1625 2400) BN 9
J 2
(-1613 2408);
DISPLAY 0.680851 (-1613 2408);
PAINT GREEN (-1613 2408);
FORCEPROP 2 LAST CDS_LIB standard
J 0
(-1675 2400);
DISPLAY INVISIBLE (-1675 2400);
FORCEPROP 1 LAST BODY_TYPE PLUMBING
J 2
(-1675 2450);
DISPLAY 0.872340 (-1675 2450);
PAINT GREEN (-1675 2450);
DISPLAY INVISIBLE (-1675 2450);
FORCEPROP 1 LAST HDL_TAP TRUE
J 2
(-2000 2275);
DISPLAY 0.872340 (-2000 2275);
DISPLAY INVISIBLE (-2000 2275);
FORCEPROP 1 LAST PATH I261
J 2
(-1673 2400);
DISPLAY 0.872340 (-1673 2400);
PAINT GREEN (-1673 2400);
DISPLAY INVISIBLE (-1673 2400);
FORCEADD TAP..1
R 2
(-1925 2750);
FORCEPROP 3 LASTPIN (-1875 2750) SIG_NAME P5E_CPU1_PE0_TX_DP<11>
J 0
(-1865 2760);
DISPLAY 0.659574 (-1865 2760);
PAINT MONO (-1865 2760);
DISPLAY INVISIBLE (-1865 2760);
FORCEPROP 1 LASTPIN (-1875 2750) BN 11
J 2
(-1863 2758);
DISPLAY 0.680851 (-1863 2758);
PAINT GREEN (-1863 2758);
FORCEPROP 2 LAST CDS_LIB standard
J 0
(-1925 2750);
DISPLAY INVISIBLE (-1925 2750);
FORCEPROP 1 LAST BODY_TYPE PLUMBING
J 2
(-1925 2800);
DISPLAY 0.872340 (-1925 2800);
PAINT GREEN (-1925 2800);
DISPLAY INVISIBLE (-1925 2800);
FORCEPROP 1 LAST HDL_TAP TRUE
J 2
(-2250 2625);
DISPLAY 0.872340 (-2250 2625);
DISPLAY INVISIBLE (-2250 2625);
FORCEPROP 1 LAST PATH I262
J 2
(-1923 2750);
DISPLAY 0.872340 (-1923 2750);
PAINT GREEN (-1923 2750);
DISPLAY INVISIBLE (-1923 2750);
FORCEADD TAP..1
R 2
(-1925 2550);
FORCEPROP 3 LASTPIN (-1875 2550) SIG_NAME P5E_CPU1_PE0_TX_DP<10>
J 0
(-1865 2560);
DISPLAY 0.659574 (-1865 2560);
PAINT MONO (-1865 2560);
DISPLAY INVISIBLE (-1865 2560);
FORCEPROP 1 LASTPIN (-1875 2550) BN 10
J 2
(-1863 2558);
DISPLAY 0.680851 (-1863 2558);
PAINT GREEN (-1863 2558);
FORCEPROP 2 LAST CDS_LIB standard
J 0
(-1925 2550);
DISPLAY INVISIBLE (-1925 2550);
FORCEPROP 1 LAST BODY_TYPE PLUMBING
J 2
(-1925 2600);
DISPLAY 0.872340 (-1925 2600);
PAINT GREEN (-1925 2600);
DISPLAY INVISIBLE (-1925 2600);
FORCEPROP 1 LAST HDL_TAP TRUE
J 2
(-2250 2425);
DISPLAY 0.872340 (-2250 2425);
DISPLAY INVISIBLE (-2250 2425);
FORCEPROP 1 LAST PATH I263
J 2
(-1923 2550);
DISPLAY 0.872340 (-1923 2550);
PAINT GREEN (-1923 2550);
DISPLAY INVISIBLE (-1923 2550);
FORCEADD TAP..1
R 2
(-1925 2950);
FORCEPROP 3 LASTPIN (-1875 2950) SIG_NAME P5E_CPU1_PE0_TX_DP<12>
J 0
(-1865 2960);
DISPLAY 0.659574 (-1865 2960);
PAINT MONO (-1865 2960);
DISPLAY INVISIBLE (-1865 2960);
FORCEPROP 1 LASTPIN (-1875 2950) BN 12
J 2
(-1863 2958);
DISPLAY 0.680851 (-1863 2958);
PAINT GREEN (-1863 2958);
FORCEPROP 2 LAST CDS_LIB standard
J 0
(-1925 2950);
DISPLAY INVISIBLE (-1925 2950);
FORCEPROP 1 LAST BODY_TYPE PLUMBING
J 2
(-1925 3000);
DISPLAY 0.872340 (-1925 3000);
PAINT GREEN (-1925 3000);
DISPLAY INVISIBLE (-1925 3000);
FORCEPROP 1 LAST HDL_TAP TRUE
J 2
(-2250 2825);
DISPLAY 0.872340 (-2250 2825);
DISPLAY INVISIBLE (-2250 2825);
FORCEPROP 1 LAST PATH I264
J 2
(-1923 2950);
DISPLAY 0.872340 (-1923 2950);
PAINT GREEN (-1923 2950);
DISPLAY INVISIBLE (-1923 2950);
FORCEADD TAP..1
R 2
(-1675 2600);
FORCEPROP 3 LASTPIN (-1625 2600) SIG_NAME P5E_CPU1_PE0_TX_DN<10>
J 0
(-1615 2610);
DISPLAY 0.659574 (-1615 2610);
PAINT MONO (-1615 2610);
DISPLAY INVISIBLE (-1615 2610);
FORCEPROP 1 LASTPIN (-1625 2600) BN 10
J 2
(-1613 2608);
DISPLAY 0.680851 (-1613 2608);
PAINT GREEN (-1613 2608);
FORCEPROP 2 LAST CDS_LIB standard
J 0
(-1675 2600);
DISPLAY INVISIBLE (-1675 2600);
FORCEPROP 1 LAST BODY_TYPE PLUMBING
J 2
(-1675 2650);
DISPLAY 0.872340 (-1675 2650);
PAINT GREEN (-1675 2650);
DISPLAY INVISIBLE (-1675 2650);
FORCEPROP 1 LAST HDL_TAP TRUE
J 2
(-2000 2475);
DISPLAY 0.872340 (-2000 2475);
DISPLAY INVISIBLE (-2000 2475);
FORCEPROP 1 LAST PATH I265
J 2
(-1673 2600);
DISPLAY 0.872340 (-1673 2600);
PAINT GREEN (-1673 2600);
DISPLAY INVISIBLE (-1673 2600);
FORCEADD TAP..1
R 2
(-1675 2800);
FORCEPROP 3 LASTPIN (-1625 2800) SIG_NAME P5E_CPU1_PE0_TX_DN<11>
J 0
(-1615 2810);
DISPLAY 0.659574 (-1615 2810);
PAINT MONO (-1615 2810);
DISPLAY INVISIBLE (-1615 2810);
FORCEPROP 1 LASTPIN (-1625 2800) BN 11
J 2
(-1613 2808);
DISPLAY 0.680851 (-1613 2808);
PAINT GREEN (-1613 2808);
FORCEPROP 2 LAST CDS_LIB standard
J 0
(-1675 2800);
DISPLAY INVISIBLE (-1675 2800);
FORCEPROP 1 LAST BODY_TYPE PLUMBING
J 2
(-1675 2850);
DISPLAY 0.872340 (-1675 2850);
PAINT GREEN (-1675 2850);
DISPLAY INVISIBLE (-1675 2850);
FORCEPROP 1 LAST HDL_TAP TRUE
J 2
(-2000 2675);
DISPLAY 0.872340 (-2000 2675);
DISPLAY INVISIBLE (-2000 2675);
FORCEPROP 1 LAST PATH I266
J 2
(-1673 2800);
DISPLAY 0.872340 (-1673 2800);
PAINT GREEN (-1673 2800);
DISPLAY INVISIBLE (-1673 2800);
FORCEADD TAP..1
R 2
(-1675 3000);
FORCEPROP 3 LASTPIN (-1625 3000) SIG_NAME P5E_CPU1_PE0_TX_DN<12>
J 0
(-1615 3010);
DISPLAY 0.659574 (-1615 3010);
PAINT MONO (-1615 3010);
DISPLAY INVISIBLE (-1615 3010);
FORCEPROP 1 LASTPIN (-1625 3000) BN 12
J 2
(-1613 3008);
DISPLAY 0.680851 (-1613 3008);
PAINT GREEN (-1613 3008);
FORCEPROP 2 LAST CDS_LIB standard
J 0
(-1675 3000);
DISPLAY INVISIBLE (-1675 3000);
FORCEPROP 1 LAST BODY_TYPE PLUMBING
J 2
(-1675 3050);
DISPLAY 0.872340 (-1675 3050);
PAINT GREEN (-1675 3050);
DISPLAY INVISIBLE (-1675 3050);
FORCEPROP 1 LAST HDL_TAP TRUE
J 2
(-2000 2875);
DISPLAY 0.872340 (-2000 2875);
DISPLAY INVISIBLE (-2000 2875);
FORCEPROP 1 LAST PATH I267
J 2
(-1673 3000);
DISPLAY 0.872340 (-1673 3000);
PAINT GREEN (-1673 3000);
DISPLAY INVISIBLE (-1673 3000);
FORCEADD TAP..1
R 2
(-1925 3150);
FORCEPROP 3 LASTPIN (-1875 3150) SIG_NAME P5E_CPU1_PE0_TX_DP<13>
J 0
(-1865 3160);
DISPLAY 0.659574 (-1865 3160);
PAINT MONO (-1865 3160);
DISPLAY INVISIBLE (-1865 3160);
FORCEPROP 1 LASTPIN (-1875 3150) BN 13
J 2
(-1863 3158);
DISPLAY 0.680851 (-1863 3158);
PAINT GREEN (-1863 3158);
FORCEPROP 2 LAST CDS_LIB standard
J 0
(-1925 3150);
DISPLAY INVISIBLE (-1925 3150);
FORCEPROP 1 LAST BODY_TYPE PLUMBING
J 2
(-1925 3200);
DISPLAY 0.872340 (-1925 3200);
PAINT GREEN (-1925 3200);
DISPLAY INVISIBLE (-1925 3200);
FORCEPROP 1 LAST HDL_TAP TRUE
J 2
(-2250 3025);
DISPLAY 0.872340 (-2250 3025);
DISPLAY INVISIBLE (-2250 3025);
FORCEPROP 1 LAST PATH I268
J 2
(-1923 3150);
DISPLAY 0.872340 (-1923 3150);
PAINT GREEN (-1923 3150);
DISPLAY INVISIBLE (-1923 3150);
FORCEADD TAP..1
R 2
(-1925 3350);
FORCEPROP 3 LASTPIN (-1875 3350) SIG_NAME P5E_CPU1_PE0_TX_DP<14>
J 0
(-1865 3360);
DISPLAY 0.659574 (-1865 3360);
PAINT MONO (-1865 3360);
DISPLAY INVISIBLE (-1865 3360);
FORCEPROP 1 LASTPIN (-1875 3350) BN 14
J 2
(-1863 3358);
DISPLAY 0.680851 (-1863 3358);
PAINT GREEN (-1863 3358);
FORCEPROP 2 LAST CDS_LIB standard
J 0
(-1925 3350);
DISPLAY INVISIBLE (-1925 3350);
FORCEPROP 1 LAST BODY_TYPE PLUMBING
J 2
(-1925 3400);
DISPLAY 0.872340 (-1925 3400);
PAINT GREEN (-1925 3400);
DISPLAY INVISIBLE (-1925 3400);
FORCEPROP 1 LAST HDL_TAP TRUE
J 2
(-2250 3225);
DISPLAY 0.872340 (-2250 3225);
DISPLAY INVISIBLE (-2250 3225);
FORCEPROP 1 LAST PATH I269
J 2
(-1923 3350);
DISPLAY 0.872340 (-1923 3350);
PAINT GREEN (-1923 3350);
DISPLAY INVISIBLE (-1923 3350);
FORCEADD TAP..1
R 2
(-1925 3550);
FORCEPROP 3 LASTPIN (-1875 3550) SIG_NAME P5E_CPU1_PE0_TX_DP<15>
J 0
(-1865 3560);
DISPLAY 0.659574 (-1865 3560);
PAINT MONO (-1865 3560);
DISPLAY INVISIBLE (-1865 3560);
FORCEPROP 1 LASTPIN (-1875 3550) BN 15
J 2
(-1863 3558);
DISPLAY 0.680851 (-1863 3558);
PAINT GREEN (-1863 3558);
FORCEPROP 2 LAST CDS_LIB standard
J 0
(-1925 3550);
DISPLAY INVISIBLE (-1925 3550);
FORCEPROP 1 LAST BODY_TYPE PLUMBING
J 2
(-1925 3600);
DISPLAY 0.872340 (-1925 3600);
PAINT GREEN (-1925 3600);
DISPLAY INVISIBLE (-1925 3600);
FORCEPROP 1 LAST HDL_TAP TRUE
J 2
(-2250 3425);
DISPLAY 0.872340 (-2250 3425);
DISPLAY INVISIBLE (-2250 3425);
FORCEPROP 1 LAST PATH I270
J 2
(-1923 3550);
DISPLAY 0.872340 (-1923 3550);
PAINT GREEN (-1923 3550);
DISPLAY INVISIBLE (-1923 3550);
FORCEADD TAP..1
R 2
(-1675 3200);
FORCEPROP 3 LASTPIN (-1625 3200) SIG_NAME P5E_CPU1_PE0_TX_DN<13>
J 0
(-1615 3210);
DISPLAY 0.659574 (-1615 3210);
PAINT MONO (-1615 3210);
DISPLAY INVISIBLE (-1615 3210);
FORCEPROP 1 LASTPIN (-1625 3200) BN 13
J 2
(-1613 3208);
DISPLAY 0.680851 (-1613 3208);
PAINT GREEN (-1613 3208);
FORCEPROP 2 LAST CDS_LIB standard
J 0
(-1675 3200);
DISPLAY INVISIBLE (-1675 3200);
FORCEPROP 1 LAST BODY_TYPE PLUMBING
J 2
(-1675 3250);
DISPLAY 0.872340 (-1675 3250);
PAINT GREEN (-1675 3250);
DISPLAY INVISIBLE (-1675 3250);
FORCEPROP 1 LAST HDL_TAP TRUE
J 2
(-2000 3075);
DISPLAY 0.872340 (-2000 3075);
DISPLAY INVISIBLE (-2000 3075);
FORCEPROP 1 LAST PATH I271
J 2
(-1673 3200);
DISPLAY 0.872340 (-1673 3200);
PAINT GREEN (-1673 3200);
DISPLAY INVISIBLE (-1673 3200);
FORCEADD TAP..1
R 2
(-1675 3400);
FORCEPROP 3 LASTPIN (-1625 3400) SIG_NAME P5E_CPU1_PE0_TX_DN<14>
J 0
(-1615 3410);
DISPLAY 0.659574 (-1615 3410);
PAINT MONO (-1615 3410);
DISPLAY INVISIBLE (-1615 3410);
FORCEPROP 1 LASTPIN (-1625 3400) BN 14
J 2
(-1613 3408);
DISPLAY 0.680851 (-1613 3408);
PAINT GREEN (-1613 3408);
FORCEPROP 2 LAST CDS_LIB standard
J 0
(-1675 3400);
DISPLAY INVISIBLE (-1675 3400);
FORCEPROP 1 LAST BODY_TYPE PLUMBING
J 2
(-1675 3450);
DISPLAY 0.872340 (-1675 3450);
PAINT GREEN (-1675 3450);
DISPLAY INVISIBLE (-1675 3450);
FORCEPROP 1 LAST HDL_TAP TRUE
J 2
(-2000 3275);
DISPLAY 0.872340 (-2000 3275);
DISPLAY INVISIBLE (-2000 3275);
FORCEPROP 1 LAST PATH I272
J 2
(-1673 3400);
DISPLAY 0.872340 (-1673 3400);
PAINT GREEN (-1673 3400);
DISPLAY INVISIBLE (-1673 3400);
FORCEADD TAP..1
R 2
(-1675 3600);
FORCEPROP 3 LASTPIN (-1625 3600) SIG_NAME P5E_CPU1_PE0_TX_DN<15>
J 0
(-1615 3610);
DISPLAY 0.659574 (-1615 3610);
PAINT MONO (-1615 3610);
DISPLAY INVISIBLE (-1615 3610);
FORCEPROP 1 LASTPIN (-1625 3600) BN 15
J 2
(-1613 3608);
DISPLAY 0.680851 (-1613 3608);
PAINT GREEN (-1613 3608);
FORCEPROP 2 LAST CDS_LIB standard
J 0
(-1675 3600);
DISPLAY INVISIBLE (-1675 3600);
FORCEPROP 1 LAST BODY_TYPE PLUMBING
J 2
(-1675 3650);
DISPLAY 0.872340 (-1675 3650);
PAINT GREEN (-1675 3650);
DISPLAY INVISIBLE (-1675 3650);
FORCEPROP 1 LAST HDL_TAP TRUE
J 2
(-2000 3475);
DISPLAY 0.872340 (-2000 3475);
DISPLAY INVISIBLE (-2000 3475);
FORCEPROP 1 LAST PATH I273
J 2
(-1673 3600);
DISPLAY 0.872340 (-1673 3600);
PAINT GREEN (-1673 3600);
DISPLAY INVISIBLE (-1673 3600);
FORCEADD Q_CAP_DIFFBUS..2
R 2
(-950 2150);
FORCEPROP 1 LAST PART_NUMBER SP_CH4221MEE01
J 2
(-1066 2238);
DISPLAY 0.574468 (-1066 2238);
PAINT GREEN (-1066 2238);
DISPLAY INVISIBLE (-1066 2238);
FORCEPROP 2 LAST VALUE DIFF BUS_0.22UF
J 2
(-1100 2150);
DISPLAY 0.553191 (-1100 2150);
FORCEPROP 1 LAST $LOCATION C725
J 2
(-716 2167);
DISPLAY 0.723404 (-716 2167);
PAINT GREEN (-716 2167);
FORCEPROP 2 LASTPIN (-875 2150) $PN 1
J 0
(-865 2160);
DISPLAY 0.808511 (-865 2160);
FORCEPROP 2 LASTPIN (-1025 2150) $PN 2
J 2
(-1035 2160);
DISPLAY 0.808511 (-1035 2160);
FORCEPROP 1 LAST CDS_LMAN_SYM_OUTLINE -25,50,25,-50
J 2
(-950 2150);
DISPLAY 0.468085 (-950 2150);
PAINT GREEN (-950 2150);
DISPLAY INVISIBLE (-950 2150);
FORCEPROP 2 LAST CDS_LIB pure_quanta
J 2
(-950 2150);
DISPLAY INVISIBLE (-950 2150);
FORCEPROP 1 LAST PIN_NAMES_ROTATE TRUE
J 2
(-950 2150);
DISPLAY 0.489362 (-950 2150);
PAINT GREEN (-950 2150);
DISPLAY INVISIBLE (-950 2150);
FORCEPROP 2 LAST VOLTAGE 6.3V
J 2
(-1300 2200);
DISPLAY 0.553191 (-1300 2200);
DISPLAY INVISIBLE (-1300 2200);
FORCEPROP 1 LAST MATERIAL X6S
J 2
(-941 2229);
DISPLAY 0.574468 (-941 2229);
PAINT GREEN (-941 2229);
DISPLAY INVISIBLE (-941 2229);
FORCEPROP 2 LAST PACK_TYPE C0201
J 2
(-1125 2200);
DISPLAY 0.553191 (-1125 2200);
DISPLAY INVISIBLE (-1125 2200);
FORCEPROP 2 LAST TOLERANCE 20%
J 2
(-1025 2200);
DISPLAY 0.553191 (-1025 2200);
DISPLAY INVISIBLE (-1025 2200);
FORCEPROP 1 LAST PATH I274
J 2
(-950 2150);
DISPLAY 0.723404 (-950 2150);
DISPLAY INVISIBLE (-950 2150);
FORCEPROP 1 LAST $LOCATION C725
J 0
(-700 2225);
DISPLAY 1.021277 (-700 2225);
DISPLAY INVISIBLE (-700 2225);
FORCEPROP 2 LAST CDS_LOCATION C725
J 0
(-700 2225);
DISPLAY 1.021277 (-700 2225);
DISPLAY INVISIBLE (-700 2225);
FORCEPROP 2 LAST $SEC 1
J 2
(-775 2225);
DISPLAY 0.680851 (-775 2225);
PAINT MONO (-775 2225);
DISPLAY INVISIBLE (-775 2225);
FORCEPROP 2 LAST CDS_SEC 1
J 2
(-775 2225);
DISPLAY 0.680851 (-775 2225);
DISPLAY INVISIBLE (-775 2225);
FORCEADD Q_CAP_DIFFBUS..2
R 2
(-950 2200);
FORCEPROP 1 LAST PART_NUMBER SP_CH4221MEE01
J 2
(-1066 2288);
DISPLAY 0.574468 (-1066 2288);
PAINT GREEN (-1066 2288);
DISPLAY INVISIBLE (-1066 2288);
FORCEPROP 2 LAST VALUE DIFF BUS_0.22UF
J 2
(-1100 2200);
DISPLAY 0.553191 (-1100 2200);
FORCEPROP 1 LAST $LOCATION C724
J 2
(-716 2217);
DISPLAY 0.723404 (-716 2217);
PAINT GREEN (-716 2217);
FORCEPROP 2 LASTPIN (-875 2200) $PN 1
J 0
(-865 2210);
DISPLAY 0.808511 (-865 2210);
FORCEPROP 2 LASTPIN (-1025 2200) $PN 2
J 2
(-1035 2210);
DISPLAY 0.808511 (-1035 2210);
FORCEPROP 1 LAST CDS_LMAN_SYM_OUTLINE -25,50,25,-50
J 2
(-950 2200);
DISPLAY 0.468085 (-950 2200);
PAINT GREEN (-950 2200);
DISPLAY INVISIBLE (-950 2200);
FORCEPROP 2 LAST CDS_LIB pure_quanta
J 2
(-950 2200);
DISPLAY INVISIBLE (-950 2200);
FORCEPROP 1 LAST PIN_NAMES_ROTATE TRUE
J 2
(-950 2200);
DISPLAY 0.489362 (-950 2200);
PAINT GREEN (-950 2200);
DISPLAY INVISIBLE (-950 2200);
FORCEPROP 2 LAST VOLTAGE 6.3V
J 2
(-1300 2250);
DISPLAY 0.553191 (-1300 2250);
DISPLAY INVISIBLE (-1300 2250);
FORCEPROP 1 LAST MATERIAL X6S
J 2
(-941 2279);
DISPLAY 0.574468 (-941 2279);
PAINT GREEN (-941 2279);
DISPLAY INVISIBLE (-941 2279);
FORCEPROP 2 LAST PACK_TYPE C0201
J 2
(-1125 2250);
DISPLAY 0.553191 (-1125 2250);
DISPLAY INVISIBLE (-1125 2250);
FORCEPROP 2 LAST TOLERANCE 20%
J 2
(-1025 2250);
DISPLAY 0.553191 (-1025 2250);
DISPLAY INVISIBLE (-1025 2250);
FORCEPROP 1 LAST PATH I275
J 2
(-950 2200);
DISPLAY 0.723404 (-950 2200);
DISPLAY INVISIBLE (-950 2200);
FORCEPROP 1 LAST $LOCATION C724
J 0
(-700 2275);
DISPLAY 1.021277 (-700 2275);
DISPLAY INVISIBLE (-700 2275);
FORCEPROP 2 LAST CDS_LOCATION C724
J 0
(-700 2275);
DISPLAY 1.021277 (-700 2275);
DISPLAY INVISIBLE (-700 2275);
FORCEPROP 2 LAST $SEC 1
J 2
(-775 2275);
DISPLAY 0.680851 (-775 2275);
PAINT MONO (-775 2275);
DISPLAY INVISIBLE (-775 2275);
FORCEPROP 2 LAST CDS_SEC 1
J 2
(-775 2275);
DISPLAY 0.680851 (-775 2275);
DISPLAY INVISIBLE (-775 2275);
FORCEADD Q_CAP_DIFFBUS..2
R 2
(-950 2400);
FORCEPROP 1 LAST PART_NUMBER SP_CH4221MEE01
J 2
(-1066 2488);
DISPLAY 0.574468 (-1066 2488);
PAINT GREEN (-1066 2488);
DISPLAY INVISIBLE (-1066 2488);
FORCEPROP 2 LAST VALUE DIFF BUS_0.22UF
J 2
(-1100 2400);
DISPLAY 0.553191 (-1100 2400);
FORCEPROP 1 LAST $LOCATION C722
J 2
(-716 2417);
DISPLAY 0.723404 (-716 2417);
PAINT GREEN (-716 2417);
FORCEPROP 2 LASTPIN (-875 2400) $PN 1
J 0
(-865 2410);
DISPLAY 0.808511 (-865 2410);
FORCEPROP 2 LASTPIN (-1025 2400) $PN 2
J 2
(-1035 2410);
DISPLAY 0.808511 (-1035 2410);
FORCEPROP 2 LAST CDS_LIB pure_quanta
J 2
(-950 2400);
DISPLAY INVISIBLE (-950 2400);
FORCEPROP 1 LAST CDS_LMAN_SYM_OUTLINE -25,50,25,-50
J 2
(-950 2400);
DISPLAY 0.468085 (-950 2400);
PAINT GREEN (-950 2400);
DISPLAY INVISIBLE (-950 2400);
FORCEPROP 1 LAST PIN_NAMES_ROTATE TRUE
J 2
(-950 2400);
DISPLAY 0.489362 (-950 2400);
PAINT GREEN (-950 2400);
DISPLAY INVISIBLE (-950 2400);
FORCEPROP 2 LAST VOLTAGE 6.3V
J 2
(-1300 2450);
DISPLAY 0.553191 (-1300 2450);
DISPLAY INVISIBLE (-1300 2450);
FORCEPROP 1 LAST MATERIAL X6S
J 2
(-941 2479);
DISPLAY 0.574468 (-941 2479);
PAINT GREEN (-941 2479);
DISPLAY INVISIBLE (-941 2479);
FORCEPROP 2 LAST PACK_TYPE C0201
J 2
(-1125 2450);
DISPLAY 0.553191 (-1125 2450);
DISPLAY INVISIBLE (-1125 2450);
FORCEPROP 2 LAST TOLERANCE 20%
J 2
(-1025 2450);
DISPLAY 0.553191 (-1025 2450);
DISPLAY INVISIBLE (-1025 2450);
FORCEPROP 1 LAST PATH I276
J 2
(-950 2400);
DISPLAY 0.723404 (-950 2400);
DISPLAY INVISIBLE (-950 2400);
FORCEPROP 1 LAST $LOCATION C722
J 0
(-700 2475);
DISPLAY 1.021277 (-700 2475);
DISPLAY INVISIBLE (-700 2475);
FORCEPROP 2 LAST CDS_LOCATION C722
J 0
(-700 2475);
DISPLAY 1.021277 (-700 2475);
DISPLAY INVISIBLE (-700 2475);
FORCEPROP 2 LAST $SEC 1
J 2
(-775 2475);
DISPLAY 0.680851 (-775 2475);
PAINT MONO (-775 2475);
DISPLAY INVISIBLE (-775 2475);
FORCEPROP 2 LAST CDS_SEC 1
J 2
(-775 2475);
DISPLAY 0.680851 (-775 2475);
DISPLAY INVISIBLE (-775 2475);
FORCEADD Q_CAP_DIFFBUS..2
R 2
(-950 2350);
FORCEPROP 1 LAST PART_NUMBER SP_CH4221MEE01
J 2
(-1066 2438);
DISPLAY 0.574468 (-1066 2438);
PAINT GREEN (-1066 2438);
DISPLAY INVISIBLE (-1066 2438);
FORCEPROP 2 LAST VALUE DIFF BUS_0.22UF
J 2
(-1100 2350);
DISPLAY 0.553191 (-1100 2350);
FORCEPROP 1 LAST $LOCATION C723
J 2
(-716 2367);
DISPLAY 0.723404 (-716 2367);
PAINT GREEN (-716 2367);
FORCEPROP 2 LASTPIN (-875 2350) $PN 1
J 0
(-865 2360);
DISPLAY 0.808511 (-865 2360);
FORCEPROP 2 LASTPIN (-1025 2350) $PN 2
J 2
(-1035 2360);
DISPLAY 0.808511 (-1035 2360);
FORCEPROP 1 LAST CDS_LMAN_SYM_OUTLINE -25,50,25,-50
J 2
(-950 2350);
DISPLAY 0.468085 (-950 2350);
PAINT GREEN (-950 2350);
DISPLAY INVISIBLE (-950 2350);
FORCEPROP 2 LAST CDS_LIB pure_quanta
J 2
(-950 2350);
DISPLAY INVISIBLE (-950 2350);
FORCEPROP 1 LAST PIN_NAMES_ROTATE TRUE
J 2
(-950 2350);
DISPLAY 0.489362 (-950 2350);
PAINT GREEN (-950 2350);
DISPLAY INVISIBLE (-950 2350);
FORCEPROP 2 LAST VOLTAGE 6.3V
J 2
(-1300 2400);
DISPLAY 0.553191 (-1300 2400);
DISPLAY INVISIBLE (-1300 2400);
FORCEPROP 1 LAST MATERIAL X6S
J 2
(-941 2429);
DISPLAY 0.574468 (-941 2429);
PAINT GREEN (-941 2429);
DISPLAY INVISIBLE (-941 2429);
FORCEPROP 2 LAST PACK_TYPE C0201
J 2
(-1125 2400);
DISPLAY 0.553191 (-1125 2400);
DISPLAY INVISIBLE (-1125 2400);
FORCEPROP 2 LAST TOLERANCE 20%
J 2
(-1025 2400);
DISPLAY 0.553191 (-1025 2400);
DISPLAY INVISIBLE (-1025 2400);
FORCEPROP 1 LAST PATH I277
J 2
(-950 2350);
DISPLAY 0.723404 (-950 2350);
DISPLAY INVISIBLE (-950 2350);
FORCEPROP 1 LAST $LOCATION C723
J 0
(-700 2425);
DISPLAY 1.021277 (-700 2425);
DISPLAY INVISIBLE (-700 2425);
FORCEPROP 2 LAST CDS_LOCATION C723
J 0
(-700 2425);
DISPLAY 1.021277 (-700 2425);
DISPLAY INVISIBLE (-700 2425);
FORCEPROP 2 LAST $SEC 1
J 2
(-775 2425);
DISPLAY 0.680851 (-775 2425);
PAINT MONO (-775 2425);
DISPLAY INVISIBLE (-775 2425);
FORCEPROP 2 LAST CDS_SEC 1
J 2
(-775 2425);
DISPLAY 0.680851 (-775 2425);
DISPLAY INVISIBLE (-775 2425);
FORCEADD Q_CAP_DIFFBUS..2
R 2
(-950 2550);
FORCEPROP 1 LAST PART_NUMBER SP_CH4221MEE01
J 2
(-1066 2638);
DISPLAY 0.574468 (-1066 2638);
PAINT GREEN (-1066 2638);
DISPLAY INVISIBLE (-1066 2638);
FORCEPROP 2 LAST VALUE DIFF BUS_0.22UF
J 2
(-1100 2550);
DISPLAY 0.553191 (-1100 2550);
FORCEPROP 1 LAST $LOCATION C721
J 2
(-716 2567);
DISPLAY 0.723404 (-716 2567);
PAINT GREEN (-716 2567);
FORCEPROP 2 LASTPIN (-875 2550) $PN 1
J 0
(-865 2560);
DISPLAY 0.808511 (-865 2560);
FORCEPROP 2 LASTPIN (-1025 2550) $PN 2
J 2
(-1035 2560);
DISPLAY 0.808511 (-1035 2560);
FORCEPROP 1 LAST CDS_LMAN_SYM_OUTLINE -25,50,25,-50
J 2
(-950 2550);
DISPLAY 0.468085 (-950 2550);
PAINT GREEN (-950 2550);
DISPLAY INVISIBLE (-950 2550);
FORCEPROP 2 LAST CDS_LIB pure_quanta
J 2
(-950 2550);
DISPLAY INVISIBLE (-950 2550);
FORCEPROP 1 LAST PIN_NAMES_ROTATE TRUE
J 2
(-950 2550);
DISPLAY 0.489362 (-950 2550);
PAINT GREEN (-950 2550);
DISPLAY INVISIBLE (-950 2550);
FORCEPROP 2 LAST VOLTAGE 6.3V
J 2
(-1300 2600);
DISPLAY 0.553191 (-1300 2600);
DISPLAY INVISIBLE (-1300 2600);
FORCEPROP 1 LAST MATERIAL X6S
J 2
(-941 2629);
DISPLAY 0.574468 (-941 2629);
PAINT GREEN (-941 2629);
DISPLAY INVISIBLE (-941 2629);
FORCEPROP 2 LAST PACK_TYPE C0201
J 2
(-1125 2600);
DISPLAY 0.553191 (-1125 2600);
DISPLAY INVISIBLE (-1125 2600);
FORCEPROP 2 LAST TOLERANCE 20%
J 2
(-1025 2600);
DISPLAY 0.553191 (-1025 2600);
DISPLAY INVISIBLE (-1025 2600);
FORCEPROP 1 LAST PATH I278
J 2
(-950 2550);
DISPLAY 0.723404 (-950 2550);
DISPLAY INVISIBLE (-950 2550);
FORCEPROP 1 LAST $LOCATION C721
J 0
(-700 2625);
DISPLAY 1.021277 (-700 2625);
DISPLAY INVISIBLE (-700 2625);
FORCEPROP 2 LAST CDS_LOCATION C721
J 0
(-700 2625);
DISPLAY 1.021277 (-700 2625);
DISPLAY INVISIBLE (-700 2625);
FORCEPROP 2 LAST $SEC 1
J 2
(-775 2625);
DISPLAY 0.680851 (-775 2625);
PAINT MONO (-775 2625);
DISPLAY INVISIBLE (-775 2625);
FORCEPROP 2 LAST CDS_SEC 1
J 2
(-775 2625);
DISPLAY 0.680851 (-775 2625);
DISPLAY INVISIBLE (-775 2625);
FORCEADD Q_CAP_DIFFBUS..2
R 2
(-950 2600);
FORCEPROP 1 LAST PART_NUMBER SP_CH4221MEE01
J 2
(-1066 2688);
DISPLAY 0.574468 (-1066 2688);
PAINT GREEN (-1066 2688);
DISPLAY INVISIBLE (-1066 2688);
FORCEPROP 2 LAST VALUE DIFF BUS_0.22UF
J 2
(-1100 2600);
DISPLAY 0.553191 (-1100 2600);
FORCEPROP 1 LAST $LOCATION C720
J 2
(-716 2617);
DISPLAY 0.723404 (-716 2617);
PAINT GREEN (-716 2617);
FORCEPROP 2 LASTPIN (-875 2600) $PN 1
J 0
(-865 2610);
DISPLAY 0.808511 (-865 2610);
FORCEPROP 2 LASTPIN (-1025 2600) $PN 2
J 2
(-1035 2610);
DISPLAY 0.808511 (-1035 2610);
FORCEPROP 1 LAST CDS_LMAN_SYM_OUTLINE -25,50,25,-50
J 2
(-950 2600);
DISPLAY 0.468085 (-950 2600);
PAINT GREEN (-950 2600);
DISPLAY INVISIBLE (-950 2600);
FORCEPROP 2 LAST CDS_LIB pure_quanta
J 2
(-950 2600);
DISPLAY INVISIBLE (-950 2600);
FORCEPROP 1 LAST PIN_NAMES_ROTATE TRUE
J 2
(-950 2600);
DISPLAY 0.489362 (-950 2600);
PAINT GREEN (-950 2600);
DISPLAY INVISIBLE (-950 2600);
FORCEPROP 2 LAST VOLTAGE 6.3V
J 2
(-1300 2650);
DISPLAY 0.553191 (-1300 2650);
DISPLAY INVISIBLE (-1300 2650);
FORCEPROP 1 LAST MATERIAL X6S
J 2
(-941 2679);
DISPLAY 0.574468 (-941 2679);
PAINT GREEN (-941 2679);
DISPLAY INVISIBLE (-941 2679);
FORCEPROP 2 LAST PACK_TYPE C0201
J 2
(-1125 2650);
DISPLAY 0.553191 (-1125 2650);
DISPLAY INVISIBLE (-1125 2650);
FORCEPROP 2 LAST TOLERANCE 20%
J 2
(-1025 2650);
DISPLAY 0.553191 (-1025 2650);
DISPLAY INVISIBLE (-1025 2650);
FORCEPROP 1 LAST PATH I279
J 2
(-950 2600);
DISPLAY 0.723404 (-950 2600);
DISPLAY INVISIBLE (-950 2600);
FORCEPROP 1 LAST $LOCATION C720
J 0
(-700 2675);
DISPLAY 1.021277 (-700 2675);
DISPLAY INVISIBLE (-700 2675);
FORCEPROP 2 LAST CDS_LOCATION C720
J 0
(-700 2675);
DISPLAY 1.021277 (-700 2675);
DISPLAY INVISIBLE (-700 2675);
FORCEPROP 2 LAST $SEC 1
J 2
(-775 2675);
DISPLAY 0.680851 (-775 2675);
PAINT MONO (-775 2675);
DISPLAY INVISIBLE (-775 2675);
FORCEPROP 2 LAST CDS_SEC 1
J 2
(-775 2675);
DISPLAY 0.680851 (-775 2675);
DISPLAY INVISIBLE (-775 2675);
FORCEADD Q_CAP_DIFFBUS..2
R 2
(-950 2750);
FORCEPROP 1 LAST PART_NUMBER SP_CH4221MEE01
J 2
(-1066 2838);
DISPLAY 0.574468 (-1066 2838);
PAINT GREEN (-1066 2838);
DISPLAY INVISIBLE (-1066 2838);
FORCEPROP 2 LAST VALUE DIFF BUS_0.22UF
J 2
(-1100 2750);
DISPLAY 0.553191 (-1100 2750);
FORCEPROP 1 LAST $LOCATION C719
J 2
(-716 2767);
DISPLAY 0.723404 (-716 2767);
PAINT GREEN (-716 2767);
FORCEPROP 2 LASTPIN (-875 2750) $PN 1
J 0
(-865 2760);
DISPLAY 0.808511 (-865 2760);
FORCEPROP 2 LASTPIN (-1025 2750) $PN 2
J 2
(-1035 2760);
DISPLAY 0.808511 (-1035 2760);
FORCEPROP 2 LAST CDS_LIB pure_quanta
J 2
(-950 2750);
DISPLAY INVISIBLE (-950 2750);
FORCEPROP 1 LAST CDS_LMAN_SYM_OUTLINE -25,50,25,-50
J 2
(-950 2750);
DISPLAY 0.468085 (-950 2750);
PAINT GREEN (-950 2750);
DISPLAY INVISIBLE (-950 2750);
FORCEPROP 1 LAST PIN_NAMES_ROTATE TRUE
J 2
(-950 2750);
DISPLAY 0.489362 (-950 2750);
PAINT GREEN (-950 2750);
DISPLAY INVISIBLE (-950 2750);
FORCEPROP 2 LAST VOLTAGE 6.3V
J 2
(-1300 2800);
DISPLAY 0.553191 (-1300 2800);
DISPLAY INVISIBLE (-1300 2800);
FORCEPROP 1 LAST MATERIAL X6S
J 2
(-941 2829);
DISPLAY 0.574468 (-941 2829);
PAINT GREEN (-941 2829);
DISPLAY INVISIBLE (-941 2829);
FORCEPROP 2 LAST PACK_TYPE C0201
J 2
(-1125 2800);
DISPLAY 0.553191 (-1125 2800);
DISPLAY INVISIBLE (-1125 2800);
FORCEPROP 2 LAST TOLERANCE 20%
J 2
(-1025 2800);
DISPLAY 0.553191 (-1025 2800);
DISPLAY INVISIBLE (-1025 2800);
FORCEPROP 1 LAST PATH I280
J 2
(-950 2750);
DISPLAY 0.723404 (-950 2750);
DISPLAY INVISIBLE (-950 2750);
FORCEPROP 1 LAST $LOCATION C719
J 0
(-700 2825);
DISPLAY 1.021277 (-700 2825);
DISPLAY INVISIBLE (-700 2825);
FORCEPROP 2 LAST CDS_LOCATION C719
J 0
(-700 2825);
DISPLAY 1.021277 (-700 2825);
DISPLAY INVISIBLE (-700 2825);
FORCEPROP 2 LAST $SEC 1
J 2
(-775 2825);
DISPLAY 0.680851 (-775 2825);
PAINT MONO (-775 2825);
DISPLAY INVISIBLE (-775 2825);
FORCEPROP 2 LAST CDS_SEC 1
J 2
(-775 2825);
DISPLAY 0.680851 (-775 2825);
DISPLAY INVISIBLE (-775 2825);
FORCEADD Q_CAP_DIFFBUS..2
R 2
(-950 2800);
FORCEPROP 1 LAST PART_NUMBER SP_CH4221MEE01
J 2
(-1066 2888);
DISPLAY 0.574468 (-1066 2888);
PAINT GREEN (-1066 2888);
DISPLAY INVISIBLE (-1066 2888);
FORCEPROP 2 LAST VALUE DIFF BUS_0.22UF
J 2
(-1100 2800);
DISPLAY 0.553191 (-1100 2800);
FORCEPROP 1 LAST $LOCATION C718
J 2
(-716 2817);
DISPLAY 0.723404 (-716 2817);
PAINT GREEN (-716 2817);
FORCEPROP 2 LASTPIN (-875 2800) $PN 1
J 0
(-865 2810);
DISPLAY 0.808511 (-865 2810);
FORCEPROP 2 LASTPIN (-1025 2800) $PN 2
J 2
(-1035 2810);
DISPLAY 0.808511 (-1035 2810);
FORCEPROP 2 LAST CDS_LIB pure_quanta
J 2
(-950 2800);
DISPLAY INVISIBLE (-950 2800);
FORCEPROP 1 LAST CDS_LMAN_SYM_OUTLINE -25,50,25,-50
J 2
(-950 2800);
DISPLAY 0.468085 (-950 2800);
PAINT GREEN (-950 2800);
DISPLAY INVISIBLE (-950 2800);
FORCEPROP 1 LAST PIN_NAMES_ROTATE TRUE
J 2
(-950 2800);
DISPLAY 0.489362 (-950 2800);
PAINT GREEN (-950 2800);
DISPLAY INVISIBLE (-950 2800);
FORCEPROP 2 LAST VOLTAGE 6.3V
J 2
(-1300 2850);
DISPLAY 0.553191 (-1300 2850);
DISPLAY INVISIBLE (-1300 2850);
FORCEPROP 1 LAST MATERIAL X6S
J 2
(-941 2879);
DISPLAY 0.574468 (-941 2879);
PAINT GREEN (-941 2879);
DISPLAY INVISIBLE (-941 2879);
FORCEPROP 2 LAST PACK_TYPE C0201
J 2
(-1125 2850);
DISPLAY 0.553191 (-1125 2850);
DISPLAY INVISIBLE (-1125 2850);
FORCEPROP 2 LAST TOLERANCE 20%
J 2
(-1025 2850);
DISPLAY 0.553191 (-1025 2850);
DISPLAY INVISIBLE (-1025 2850);
FORCEPROP 1 LAST PATH I281
J 2
(-950 2800);
DISPLAY 0.723404 (-950 2800);
DISPLAY INVISIBLE (-950 2800);
FORCEPROP 1 LAST $LOCATION C718
J 0
(-700 2875);
DISPLAY 1.021277 (-700 2875);
DISPLAY INVISIBLE (-700 2875);
FORCEPROP 2 LAST CDS_LOCATION C718
J 0
(-700 2875);
DISPLAY 1.021277 (-700 2875);
DISPLAY INVISIBLE (-700 2875);
FORCEPROP 2 LAST $SEC 1
J 2
(-775 2875);
DISPLAY 0.680851 (-775 2875);
PAINT MONO (-775 2875);
DISPLAY INVISIBLE (-775 2875);
FORCEPROP 2 LAST CDS_SEC 1
J 2
(-775 2875);
DISPLAY 0.680851 (-775 2875);
DISPLAY INVISIBLE (-775 2875);
FORCEADD Q_CAP_DIFFBUS..2
R 2
(-950 2950);
FORCEPROP 1 LAST PART_NUMBER SP_CH4221MEE01
J 2
(-1066 3038);
DISPLAY 0.574468 (-1066 3038);
PAINT GREEN (-1066 3038);
DISPLAY INVISIBLE (-1066 3038);
FORCEPROP 2 LAST VALUE DIFF BUS_0.22UF
J 2
(-1100 2950);
DISPLAY 0.553191 (-1100 2950);
FORCEPROP 1 LAST $LOCATION C717
J 2
(-716 2967);
DISPLAY 0.723404 (-716 2967);
PAINT GREEN (-716 2967);
FORCEPROP 2 LASTPIN (-875 2950) $PN 1
J 0
(-865 2960);
DISPLAY 0.808511 (-865 2960);
FORCEPROP 2 LASTPIN (-1025 2950) $PN 2
J 2
(-1035 2960);
DISPLAY 0.808511 (-1035 2960);
FORCEPROP 1 LAST CDS_LMAN_SYM_OUTLINE -25,50,25,-50
J 2
(-950 2950);
DISPLAY 0.468085 (-950 2950);
PAINT GREEN (-950 2950);
DISPLAY INVISIBLE (-950 2950);
FORCEPROP 2 LAST CDS_LIB pure_quanta
J 2
(-950 2950);
DISPLAY INVISIBLE (-950 2950);
FORCEPROP 1 LAST PIN_NAMES_ROTATE TRUE
J 2
(-950 2950);
DISPLAY 0.489362 (-950 2950);
PAINT GREEN (-950 2950);
DISPLAY INVISIBLE (-950 2950);
FORCEPROP 2 LAST VOLTAGE 6.3V
J 2
(-1300 3000);
DISPLAY 0.553191 (-1300 3000);
DISPLAY INVISIBLE (-1300 3000);
FORCEPROP 1 LAST MATERIAL X6S
J 2
(-941 3029);
DISPLAY 0.574468 (-941 3029);
PAINT GREEN (-941 3029);
DISPLAY INVISIBLE (-941 3029);
FORCEPROP 2 LAST PACK_TYPE C0201
J 2
(-1125 3000);
DISPLAY 0.553191 (-1125 3000);
DISPLAY INVISIBLE (-1125 3000);
FORCEPROP 2 LAST TOLERANCE 20%
J 2
(-1025 3000);
DISPLAY 0.553191 (-1025 3000);
DISPLAY INVISIBLE (-1025 3000);
FORCEPROP 1 LAST PATH I282
J 2
(-950 2950);
DISPLAY 0.723404 (-950 2950);
DISPLAY INVISIBLE (-950 2950);
FORCEPROP 1 LAST $LOCATION C717
J 0
(-700 3025);
DISPLAY 1.021277 (-700 3025);
DISPLAY INVISIBLE (-700 3025);
FORCEPROP 2 LAST CDS_LOCATION C717
J 0
(-700 3025);
DISPLAY 1.021277 (-700 3025);
DISPLAY INVISIBLE (-700 3025);
FORCEPROP 2 LAST $SEC 1
J 2
(-775 3025);
DISPLAY 0.680851 (-775 3025);
PAINT MONO (-775 3025);
DISPLAY INVISIBLE (-775 3025);
FORCEPROP 2 LAST CDS_SEC 1
J 2
(-775 3025);
DISPLAY 0.680851 (-775 3025);
DISPLAY INVISIBLE (-775 3025);
FORCEADD Q_CAP_DIFFBUS..2
R 2
(-950 3000);
FORCEPROP 1 LAST PART_NUMBER SP_CH4221MEE01
J 2
(-1066 3088);
DISPLAY 0.574468 (-1066 3088);
PAINT GREEN (-1066 3088);
DISPLAY INVISIBLE (-1066 3088);
FORCEPROP 2 LAST VALUE DIFF BUS_0.22UF
J 2
(-1100 3000);
DISPLAY 0.553191 (-1100 3000);
FORCEPROP 1 LAST $LOCATION C716
J 2
(-716 3017);
DISPLAY 0.723404 (-716 3017);
PAINT GREEN (-716 3017);
FORCEPROP 2 LASTPIN (-875 3000) $PN 1
J 0
(-865 3010);
DISPLAY 0.808511 (-865 3010);
FORCEPROP 2 LASTPIN (-1025 3000) $PN 2
J 2
(-1035 3010);
DISPLAY 0.808511 (-1035 3010);
FORCEPROP 1 LAST CDS_LMAN_SYM_OUTLINE -25,50,25,-50
J 2
(-950 3000);
DISPLAY 0.468085 (-950 3000);
PAINT GREEN (-950 3000);
DISPLAY INVISIBLE (-950 3000);
FORCEPROP 2 LAST CDS_LIB pure_quanta
J 2
(-950 3000);
DISPLAY INVISIBLE (-950 3000);
FORCEPROP 1 LAST PIN_NAMES_ROTATE TRUE
J 2
(-950 3000);
DISPLAY 0.489362 (-950 3000);
PAINT GREEN (-950 3000);
DISPLAY INVISIBLE (-950 3000);
FORCEPROP 2 LAST VOLTAGE 6.3V
J 2
(-1300 3050);
DISPLAY 0.553191 (-1300 3050);
DISPLAY INVISIBLE (-1300 3050);
FORCEPROP 1 LAST MATERIAL X6S
J 2
(-941 3079);
DISPLAY 0.574468 (-941 3079);
PAINT GREEN (-941 3079);
DISPLAY INVISIBLE (-941 3079);
FORCEPROP 2 LAST PACK_TYPE C0201
J 2
(-1125 3050);
DISPLAY 0.553191 (-1125 3050);
DISPLAY INVISIBLE (-1125 3050);
FORCEPROP 2 LAST TOLERANCE 20%
J 2
(-1025 3050);
DISPLAY 0.553191 (-1025 3050);
DISPLAY INVISIBLE (-1025 3050);
FORCEPROP 1 LAST PATH I283
J 2
(-950 3000);
DISPLAY 0.723404 (-950 3000);
DISPLAY INVISIBLE (-950 3000);
FORCEPROP 1 LAST $LOCATION C716
J 0
(-700 3075);
DISPLAY 1.021277 (-700 3075);
DISPLAY INVISIBLE (-700 3075);
FORCEPROP 2 LAST CDS_LOCATION C716
J 0
(-700 3075);
DISPLAY 1.021277 (-700 3075);
DISPLAY INVISIBLE (-700 3075);
FORCEPROP 2 LAST $SEC 1
J 2
(-775 3075);
DISPLAY 0.680851 (-775 3075);
PAINT MONO (-775 3075);
DISPLAY INVISIBLE (-775 3075);
FORCEPROP 2 LAST CDS_SEC 1
J 2
(-775 3075);
DISPLAY 0.680851 (-775 3075);
DISPLAY INVISIBLE (-775 3075);
FORCEADD TAP..1
(-400 2200);
FORCEPROP 3 LASTPIN (-450 2200) SIG_NAME P5E_CPU1_PE0_TX_C_DN<8>
J 0
(-440 2210);
DISPLAY 0.659574 (-440 2210);
PAINT MONO (-440 2210);
DISPLAY INVISIBLE (-440 2210);
FORCEPROP 1 LASTPIN (-450 2200) BN 8
J 0
(-462 2208);
DISPLAY 0.680851 (-462 2208);
PAINT GREEN (-462 2208);
FORCEPROP 2 LAST CDS_LIB standard
J 0
(-400 2200);
DISPLAY INVISIBLE (-400 2200);
FORCEPROP 1 LAST BODY_TYPE PLUMBING
J 0
(-400 2250);
DISPLAY 0.872340 (-400 2250);
PAINT GREEN (-400 2250);
DISPLAY INVISIBLE (-400 2250);
FORCEPROP 1 LAST HDL_TAP TRUE
J 0
(-75 2075);
DISPLAY 0.872340 (-75 2075);
DISPLAY INVISIBLE (-75 2075);
FORCEPROP 1 LAST PATH I284
J 0
(-402 2200);
DISPLAY 0.872340 (-402 2200);
PAINT GREEN (-402 2200);
DISPLAY INVISIBLE (-402 2200);
FORCEADD TAP..1
(-400 2400);
FORCEPROP 3 LASTPIN (-450 2400) SIG_NAME P5E_CPU1_PE0_TX_C_DN<9>
J 0
(-440 2410);
DISPLAY 0.659574 (-440 2410);
PAINT MONO (-440 2410);
DISPLAY INVISIBLE (-440 2410);
FORCEPROP 1 LASTPIN (-450 2400) BN 9
J 0
(-462 2408);
DISPLAY 0.680851 (-462 2408);
PAINT GREEN (-462 2408);
FORCEPROP 2 LAST CDS_LIB standard
J 0
(-400 2400);
DISPLAY INVISIBLE (-400 2400);
FORCEPROP 1 LAST BODY_TYPE PLUMBING
J 0
(-400 2450);
DISPLAY 0.872340 (-400 2450);
PAINT GREEN (-400 2450);
DISPLAY INVISIBLE (-400 2450);
FORCEPROP 1 LAST HDL_TAP TRUE
J 0
(-75 2275);
DISPLAY 0.872340 (-75 2275);
DISPLAY INVISIBLE (-75 2275);
FORCEPROP 1 LAST PATH I285
J 0
(-402 2400);
DISPLAY 0.872340 (-402 2400);
PAINT GREEN (-402 2400);
DISPLAY INVISIBLE (-402 2400);
FORCEADD TAP..1
(-200 2150);
FORCEPROP 3 LASTPIN (-250 2150) SIG_NAME P5E_CPU1_PE0_TX_C_DP<8>
J 0
(-240 2160);
DISPLAY 0.659574 (-240 2160);
PAINT MONO (-240 2160);
DISPLAY INVISIBLE (-240 2160);
FORCEPROP 1 LASTPIN (-250 2150) BN 8
J 0
(-262 2158);
DISPLAY 0.680851 (-262 2158);
PAINT GREEN (-262 2158);
FORCEPROP 2 LAST CDS_LIB standard
J 0
(-200 2150);
DISPLAY INVISIBLE (-200 2150);
FORCEPROP 1 LAST BODY_TYPE PLUMBING
J 0
(-200 2200);
DISPLAY 0.872340 (-200 2200);
PAINT GREEN (-200 2200);
DISPLAY INVISIBLE (-200 2200);
FORCEPROP 1 LAST HDL_TAP TRUE
J 0
(125 2025);
DISPLAY 0.872340 (125 2025);
DISPLAY INVISIBLE (125 2025);
FORCEPROP 1 LAST PATH I286
J 0
(-202 2150);
DISPLAY 0.872340 (-202 2150);
PAINT GREEN (-202 2150);
DISPLAY INVISIBLE (-202 2150);
FORCEADD TAP..1
(-200 2350);
FORCEPROP 3 LASTPIN (-250 2350) SIG_NAME P5E_CPU1_PE0_TX_C_DP<9>
J 0
(-240 2360);
DISPLAY 0.659574 (-240 2360);
PAINT MONO (-240 2360);
DISPLAY INVISIBLE (-240 2360);
FORCEPROP 1 LASTPIN (-250 2350) BN 9
J 0
(-262 2358);
DISPLAY 0.680851 (-262 2358);
PAINT GREEN (-262 2358);
FORCEPROP 2 LAST CDS_LIB standard
J 0
(-200 2350);
DISPLAY INVISIBLE (-200 2350);
FORCEPROP 1 LAST BODY_TYPE PLUMBING
J 0
(-200 2400);
DISPLAY 0.872340 (-200 2400);
PAINT GREEN (-200 2400);
DISPLAY INVISIBLE (-200 2400);
FORCEPROP 1 LAST HDL_TAP TRUE
J 0
(125 2225);
DISPLAY 0.872340 (125 2225);
DISPLAY INVISIBLE (125 2225);
FORCEPROP 1 LAST PATH I287
J 0
(-202 2350);
DISPLAY 0.872340 (-202 2350);
PAINT GREEN (-202 2350);
DISPLAY INVISIBLE (-202 2350);
FORCEADD TAP..1
(-400 2600);
FORCEPROP 3 LASTPIN (-450 2600) SIG_NAME P5E_CPU1_PE0_TX_C_DN<10>
J 0
(-440 2610);
DISPLAY 0.659574 (-440 2610);
PAINT MONO (-440 2610);
DISPLAY INVISIBLE (-440 2610);
FORCEPROP 1 LASTPIN (-450 2600) BN 10
J 0
(-462 2608);
DISPLAY 0.680851 (-462 2608);
PAINT GREEN (-462 2608);
FORCEPROP 2 LAST CDS_LIB standard
J 0
(-400 2600);
DISPLAY INVISIBLE (-400 2600);
FORCEPROP 1 LAST BODY_TYPE PLUMBING
J 0
(-400 2650);
DISPLAY 0.872340 (-400 2650);
PAINT GREEN (-400 2650);
DISPLAY INVISIBLE (-400 2650);
FORCEPROP 1 LAST HDL_TAP TRUE
J 0
(-75 2475);
DISPLAY 0.872340 (-75 2475);
DISPLAY INVISIBLE (-75 2475);
FORCEPROP 1 LAST PATH I288
J 0
(-402 2600);
DISPLAY 0.872340 (-402 2600);
PAINT GREEN (-402 2600);
DISPLAY INVISIBLE (-402 2600);
FORCEADD TAP..1
(-400 3000);
FORCEPROP 3 LASTPIN (-450 3000) SIG_NAME P5E_CPU1_PE0_TX_C_DN<12>
J 0
(-440 3010);
DISPLAY 0.659574 (-440 3010);
PAINT MONO (-440 3010);
DISPLAY INVISIBLE (-440 3010);
FORCEPROP 1 LASTPIN (-450 3000) BN 12
J 0
(-462 3008);
DISPLAY 0.680851 (-462 3008);
PAINT GREEN (-462 3008);
FORCEPROP 2 LAST CDS_LIB standard
J 0
(-400 3000);
DISPLAY INVISIBLE (-400 3000);
FORCEPROP 1 LAST BODY_TYPE PLUMBING
J 0
(-400 3050);
DISPLAY 0.872340 (-400 3050);
PAINT GREEN (-400 3050);
DISPLAY INVISIBLE (-400 3050);
FORCEPROP 1 LAST HDL_TAP TRUE
J 0
(-75 2875);
DISPLAY 0.872340 (-75 2875);
DISPLAY INVISIBLE (-75 2875);
FORCEPROP 1 LAST PATH I289
J 0
(-402 3000);
DISPLAY 0.872340 (-402 3000);
PAINT GREEN (-402 3000);
DISPLAY INVISIBLE (-402 3000);
FORCEADD TAP..1
(-400 2800);
FORCEPROP 3 LASTPIN (-450 2800) SIG_NAME P5E_CPU1_PE0_TX_C_DN<11>
J 0
(-440 2810);
DISPLAY 0.659574 (-440 2810);
PAINT MONO (-440 2810);
DISPLAY INVISIBLE (-440 2810);
FORCEPROP 1 LASTPIN (-450 2800) BN 11
J 0
(-462 2808);
DISPLAY 0.680851 (-462 2808);
PAINT GREEN (-462 2808);
FORCEPROP 2 LAST CDS_LIB standard
J 0
(-400 2800);
DISPLAY INVISIBLE (-400 2800);
FORCEPROP 1 LAST BODY_TYPE PLUMBING
J 0
(-400 2850);
DISPLAY 0.872340 (-400 2850);
PAINT GREEN (-400 2850);
DISPLAY INVISIBLE (-400 2850);
FORCEPROP 1 LAST HDL_TAP TRUE
J 0
(-75 2675);
DISPLAY 0.872340 (-75 2675);
DISPLAY INVISIBLE (-75 2675);
FORCEPROP 1 LAST PATH I290
J 0
(-402 2800);
DISPLAY 0.872340 (-402 2800);
PAINT GREEN (-402 2800);
DISPLAY INVISIBLE (-402 2800);
FORCEADD TAP..1
(-200 2550);
FORCEPROP 3 LASTPIN (-250 2550) SIG_NAME P5E_CPU1_PE0_TX_C_DP<10>
J 0
(-240 2560);
DISPLAY 0.659574 (-240 2560);
PAINT MONO (-240 2560);
DISPLAY INVISIBLE (-240 2560);
FORCEPROP 1 LASTPIN (-250 2550) BN 10
J 0
(-262 2558);
DISPLAY 0.680851 (-262 2558);
PAINT GREEN (-262 2558);
FORCEPROP 2 LAST CDS_LIB standard
J 0
(-200 2550);
DISPLAY INVISIBLE (-200 2550);
FORCEPROP 1 LAST BODY_TYPE PLUMBING
J 0
(-200 2600);
DISPLAY 0.872340 (-200 2600);
PAINT GREEN (-200 2600);
DISPLAY INVISIBLE (-200 2600);
FORCEPROP 1 LAST HDL_TAP TRUE
J 0
(125 2425);
DISPLAY 0.872340 (125 2425);
DISPLAY INVISIBLE (125 2425);
FORCEPROP 1 LAST PATH I291
J 0
(-202 2550);
DISPLAY 0.872340 (-202 2550);
PAINT GREEN (-202 2550);
DISPLAY INVISIBLE (-202 2550);
FORCEADD TAP..1
(-200 2750);
FORCEPROP 3 LASTPIN (-250 2750) SIG_NAME P5E_CPU1_PE0_TX_C_DP<11>
J 0
(-240 2760);
DISPLAY 0.659574 (-240 2760);
PAINT MONO (-240 2760);
DISPLAY INVISIBLE (-240 2760);
FORCEPROP 1 LASTPIN (-250 2750) BN 11
J 0
(-262 2758);
DISPLAY 0.680851 (-262 2758);
PAINT GREEN (-262 2758);
FORCEPROP 2 LAST CDS_LIB standard
J 0
(-200 2750);
DISPLAY INVISIBLE (-200 2750);
FORCEPROP 1 LAST BODY_TYPE PLUMBING
J 0
(-200 2800);
DISPLAY 0.872340 (-200 2800);
PAINT GREEN (-200 2800);
DISPLAY INVISIBLE (-200 2800);
FORCEPROP 1 LAST HDL_TAP TRUE
J 0
(125 2625);
DISPLAY 0.872340 (125 2625);
DISPLAY INVISIBLE (125 2625);
FORCEPROP 1 LAST PATH I292
J 0
(-202 2750);
DISPLAY 0.872340 (-202 2750);
PAINT GREEN (-202 2750);
DISPLAY INVISIBLE (-202 2750);
FORCEADD TAP..1
(-200 2950);
FORCEPROP 3 LASTPIN (-250 2950) SIG_NAME P5E_CPU1_PE0_TX_C_DP<12>
J 0
(-240 2960);
DISPLAY 0.659574 (-240 2960);
PAINT MONO (-240 2960);
DISPLAY INVISIBLE (-240 2960);
FORCEPROP 1 LASTPIN (-250 2950) BN 12
J 0
(-262 2958);
DISPLAY 0.680851 (-262 2958);
PAINT GREEN (-262 2958);
FORCEPROP 2 LAST CDS_LIB standard
J 0
(-200 2950);
DISPLAY INVISIBLE (-200 2950);
FORCEPROP 1 LAST BODY_TYPE PLUMBING
J 0
(-200 3000);
DISPLAY 0.872340 (-200 3000);
PAINT GREEN (-200 3000);
DISPLAY INVISIBLE (-200 3000);
FORCEPROP 1 LAST HDL_TAP TRUE
J 0
(125 2825);
DISPLAY 0.872340 (125 2825);
DISPLAY INVISIBLE (125 2825);
FORCEPROP 1 LAST PATH I293
J 0
(-202 2950);
DISPLAY 0.872340 (-202 2950);
PAINT GREEN (-202 2950);
DISPLAY INVISIBLE (-202 2950);
FORCEADD Q_CAP_DIFFBUS..2
R 2
(-950 3150);
FORCEPROP 1 LAST PART_NUMBER SP_CH4221MEE01
J 2
(-1066 3238);
DISPLAY 0.574468 (-1066 3238);
PAINT GREEN (-1066 3238);
DISPLAY INVISIBLE (-1066 3238);
FORCEPROP 2 LAST VALUE DIFF BUS_0.22UF
J 2
(-1100 3150);
DISPLAY 0.553191 (-1100 3150);
FORCEPROP 1 LAST $LOCATION C715
J 2
(-716 3167);
DISPLAY 0.723404 (-716 3167);
PAINT GREEN (-716 3167);
FORCEPROP 2 LASTPIN (-875 3150) $PN 1
J 0
(-865 3160);
DISPLAY 0.808511 (-865 3160);
FORCEPROP 2 LASTPIN (-1025 3150) $PN 2
J 2
(-1035 3160);
DISPLAY 0.808511 (-1035 3160);
FORCEPROP 1 LAST CDS_LMAN_SYM_OUTLINE -25,50,25,-50
J 2
(-950 3150);
DISPLAY 0.468085 (-950 3150);
PAINT GREEN (-950 3150);
DISPLAY INVISIBLE (-950 3150);
FORCEPROP 2 LAST CDS_LIB pure_quanta
J 2
(-950 3150);
DISPLAY INVISIBLE (-950 3150);
FORCEPROP 1 LAST PIN_NAMES_ROTATE TRUE
J 2
(-950 3150);
DISPLAY 0.489362 (-950 3150);
PAINT GREEN (-950 3150);
DISPLAY INVISIBLE (-950 3150);
FORCEPROP 2 LAST VOLTAGE 6.3V
J 2
(-1300 3200);
DISPLAY 0.553191 (-1300 3200);
DISPLAY INVISIBLE (-1300 3200);
FORCEPROP 1 LAST MATERIAL X6S
J 2
(-941 3229);
DISPLAY 0.574468 (-941 3229);
PAINT GREEN (-941 3229);
DISPLAY INVISIBLE (-941 3229);
FORCEPROP 2 LAST PACK_TYPE C0201
J 2
(-1125 3200);
DISPLAY 0.553191 (-1125 3200);
DISPLAY INVISIBLE (-1125 3200);
FORCEPROP 2 LAST TOLERANCE 20%
J 2
(-1025 3200);
DISPLAY 0.553191 (-1025 3200);
DISPLAY INVISIBLE (-1025 3200);
FORCEPROP 1 LAST PATH I294
J 2
(-950 3150);
DISPLAY 0.723404 (-950 3150);
DISPLAY INVISIBLE (-950 3150);
FORCEPROP 1 LAST $LOCATION C715
J 0
(-700 3225);
DISPLAY 1.021277 (-700 3225);
DISPLAY INVISIBLE (-700 3225);
FORCEPROP 2 LAST CDS_LOCATION C715
J 0
(-700 3225);
DISPLAY 1.021277 (-700 3225);
DISPLAY INVISIBLE (-700 3225);
FORCEPROP 2 LAST $SEC 1
J 2
(-775 3225);
DISPLAY 0.680851 (-775 3225);
PAINT MONO (-775 3225);
DISPLAY INVISIBLE (-775 3225);
FORCEPROP 2 LAST CDS_SEC 1
J 2
(-775 3225);
DISPLAY 0.680851 (-775 3225);
DISPLAY INVISIBLE (-775 3225);
FORCEADD Q_CAP_DIFFBUS..2
R 2
(-950 3200);
FORCEPROP 1 LAST PART_NUMBER SP_CH4221MEE01
J 2
(-1066 3288);
DISPLAY 0.574468 (-1066 3288);
PAINT GREEN (-1066 3288);
DISPLAY INVISIBLE (-1066 3288);
FORCEPROP 2 LAST VALUE DIFF BUS_0.22UF
J 2
(-1100 3200);
DISPLAY 0.553191 (-1100 3200);
FORCEPROP 1 LAST $LOCATION C714
J 2
(-716 3217);
DISPLAY 0.723404 (-716 3217);
PAINT GREEN (-716 3217);
FORCEPROP 2 LASTPIN (-875 3200) $PN 1
J 0
(-865 3210);
DISPLAY 0.808511 (-865 3210);
FORCEPROP 2 LASTPIN (-1025 3200) $PN 2
J 2
(-1035 3210);
DISPLAY 0.808511 (-1035 3210);
FORCEPROP 1 LAST CDS_LMAN_SYM_OUTLINE -25,50,25,-50
J 2
(-950 3200);
DISPLAY 0.468085 (-950 3200);
PAINT GREEN (-950 3200);
DISPLAY INVISIBLE (-950 3200);
FORCEPROP 2 LAST CDS_LIB pure_quanta
J 2
(-950 3200);
DISPLAY INVISIBLE (-950 3200);
FORCEPROP 1 LAST PIN_NAMES_ROTATE TRUE
J 2
(-950 3200);
DISPLAY 0.489362 (-950 3200);
PAINT GREEN (-950 3200);
DISPLAY INVISIBLE (-950 3200);
FORCEPROP 2 LAST VOLTAGE 6.3V
J 2
(-1300 3250);
DISPLAY 0.553191 (-1300 3250);
DISPLAY INVISIBLE (-1300 3250);
FORCEPROP 1 LAST MATERIAL X6S
J 2
(-941 3279);
DISPLAY 0.574468 (-941 3279);
PAINT GREEN (-941 3279);
DISPLAY INVISIBLE (-941 3279);
FORCEPROP 2 LAST PACK_TYPE C0201
J 2
(-1125 3250);
DISPLAY 0.553191 (-1125 3250);
DISPLAY INVISIBLE (-1125 3250);
FORCEPROP 2 LAST TOLERANCE 20%
J 2
(-1025 3250);
DISPLAY 0.553191 (-1025 3250);
DISPLAY INVISIBLE (-1025 3250);
FORCEPROP 1 LAST PATH I295
J 2
(-950 3200);
DISPLAY 0.723404 (-950 3200);
DISPLAY INVISIBLE (-950 3200);
FORCEPROP 1 LAST $LOCATION C714
J 0
(-700 3275);
DISPLAY 1.021277 (-700 3275);
DISPLAY INVISIBLE (-700 3275);
FORCEPROP 2 LAST CDS_LOCATION C714
J 0
(-700 3275);
DISPLAY 1.021277 (-700 3275);
DISPLAY INVISIBLE (-700 3275);
FORCEPROP 2 LAST $SEC 1
J 2
(-775 3275);
DISPLAY 0.680851 (-775 3275);
PAINT MONO (-775 3275);
DISPLAY INVISIBLE (-775 3275);
FORCEPROP 2 LAST CDS_SEC 1
J 2
(-775 3275);
DISPLAY 0.680851 (-775 3275);
DISPLAY INVISIBLE (-775 3275);
FORCEADD Q_CAP_DIFFBUS..2
R 2
(-950 3400);
FORCEPROP 1 LAST PART_NUMBER SP_CH4221MEE01
J 2
(-1066 3488);
DISPLAY 0.574468 (-1066 3488);
PAINT GREEN (-1066 3488);
DISPLAY INVISIBLE (-1066 3488);
FORCEPROP 2 LAST VALUE DIFF BUS_0.22UF
J 2
(-1100 3400);
DISPLAY 0.553191 (-1100 3400);
FORCEPROP 1 LAST $LOCATION C712
J 2
(-716 3417);
DISPLAY 0.723404 (-716 3417);
PAINT GREEN (-716 3417);
FORCEPROP 2 LASTPIN (-875 3400) $PN 1
J 0
(-865 3410);
DISPLAY 0.808511 (-865 3410);
FORCEPROP 2 LASTPIN (-1025 3400) $PN 2
J 2
(-1035 3410);
DISPLAY 0.808511 (-1035 3410);
FORCEPROP 1 LAST CDS_LMAN_SYM_OUTLINE -25,50,25,-50
J 2
(-950 3400);
DISPLAY 0.468085 (-950 3400);
PAINT GREEN (-950 3400);
DISPLAY INVISIBLE (-950 3400);
FORCEPROP 2 LAST CDS_LIB pure_quanta
J 2
(-950 3400);
DISPLAY INVISIBLE (-950 3400);
FORCEPROP 1 LAST PIN_NAMES_ROTATE TRUE
J 2
(-950 3400);
DISPLAY 0.489362 (-950 3400);
PAINT GREEN (-950 3400);
DISPLAY INVISIBLE (-950 3400);
FORCEPROP 2 LAST VOLTAGE 6.3V
J 2
(-1300 3450);
DISPLAY 0.553191 (-1300 3450);
DISPLAY INVISIBLE (-1300 3450);
FORCEPROP 1 LAST MATERIAL X6S
J 2
(-941 3479);
DISPLAY 0.574468 (-941 3479);
PAINT GREEN (-941 3479);
DISPLAY INVISIBLE (-941 3479);
FORCEPROP 2 LAST PACK_TYPE C0201
J 2
(-1125 3450);
DISPLAY 0.553191 (-1125 3450);
DISPLAY INVISIBLE (-1125 3450);
FORCEPROP 2 LAST TOLERANCE 20%
J 2
(-1025 3450);
DISPLAY 0.553191 (-1025 3450);
DISPLAY INVISIBLE (-1025 3450);
FORCEPROP 1 LAST PATH I296
J 2
(-950 3400);
DISPLAY 0.723404 (-950 3400);
DISPLAY INVISIBLE (-950 3400);
FORCEPROP 1 LAST $LOCATION C712
J 0
(-700 3475);
DISPLAY 1.021277 (-700 3475);
DISPLAY INVISIBLE (-700 3475);
FORCEPROP 2 LAST CDS_LOCATION C712
J 0
(-700 3475);
DISPLAY 1.021277 (-700 3475);
DISPLAY INVISIBLE (-700 3475);
FORCEPROP 2 LAST $SEC 1
J 2
(-775 3475);
DISPLAY 0.680851 (-775 3475);
PAINT MONO (-775 3475);
DISPLAY INVISIBLE (-775 3475);
FORCEPROP 2 LAST CDS_SEC 1
J 2
(-775 3475);
DISPLAY 0.680851 (-775 3475);
DISPLAY INVISIBLE (-775 3475);
FORCEADD Q_CAP_DIFFBUS..2
R 2
(-950 3350);
FORCEPROP 1 LAST PART_NUMBER SP_CH4221MEE01
J 2
(-1066 3438);
DISPLAY 0.574468 (-1066 3438);
PAINT GREEN (-1066 3438);
DISPLAY INVISIBLE (-1066 3438);
FORCEPROP 2 LAST VALUE DIFF BUS_0.22UF
J 2
(-1100 3350);
DISPLAY 0.553191 (-1100 3350);
FORCEPROP 1 LAST $LOCATION C713
J 2
(-716 3367);
DISPLAY 0.723404 (-716 3367);
PAINT GREEN (-716 3367);
FORCEPROP 2 LASTPIN (-875 3350) $PN 1
J 0
(-865 3360);
DISPLAY 0.808511 (-865 3360);
FORCEPROP 2 LASTPIN (-1025 3350) $PN 2
J 2
(-1035 3360);
DISPLAY 0.808511 (-1035 3360);
FORCEPROP 1 LAST CDS_LMAN_SYM_OUTLINE -25,50,25,-50
J 2
(-950 3350);
DISPLAY 0.468085 (-950 3350);
PAINT GREEN (-950 3350);
DISPLAY INVISIBLE (-950 3350);
FORCEPROP 2 LAST CDS_LIB pure_quanta
J 2
(-950 3350);
DISPLAY INVISIBLE (-950 3350);
FORCEPROP 1 LAST PIN_NAMES_ROTATE TRUE
J 2
(-950 3350);
DISPLAY 0.489362 (-950 3350);
PAINT GREEN (-950 3350);
DISPLAY INVISIBLE (-950 3350);
FORCEPROP 2 LAST VOLTAGE 6.3V
J 2
(-1300 3400);
DISPLAY 0.553191 (-1300 3400);
DISPLAY INVISIBLE (-1300 3400);
FORCEPROP 1 LAST MATERIAL X6S
J 2
(-941 3429);
DISPLAY 0.574468 (-941 3429);
PAINT GREEN (-941 3429);
DISPLAY INVISIBLE (-941 3429);
FORCEPROP 2 LAST PACK_TYPE C0201
J 2
(-1125 3400);
DISPLAY 0.553191 (-1125 3400);
DISPLAY INVISIBLE (-1125 3400);
FORCEPROP 2 LAST TOLERANCE 20%
J 2
(-1025 3400);
DISPLAY 0.553191 (-1025 3400);
DISPLAY INVISIBLE (-1025 3400);
FORCEPROP 1 LAST PATH I297
J 2
(-950 3350);
DISPLAY 0.723404 (-950 3350);
DISPLAY INVISIBLE (-950 3350);
FORCEPROP 1 LAST $LOCATION C713
J 0
(-700 3425);
DISPLAY 1.021277 (-700 3425);
DISPLAY INVISIBLE (-700 3425);
FORCEPROP 2 LAST CDS_LOCATION C713
J 0
(-700 3425);
DISPLAY 1.021277 (-700 3425);
DISPLAY INVISIBLE (-700 3425);
FORCEPROP 2 LAST $SEC 1
J 2
(-775 3425);
DISPLAY 0.680851 (-775 3425);
PAINT MONO (-775 3425);
DISPLAY INVISIBLE (-775 3425);
FORCEPROP 2 LAST CDS_SEC 1
J 2
(-775 3425);
DISPLAY 0.680851 (-775 3425);
DISPLAY INVISIBLE (-775 3425);
FORCEADD Q_CAP_DIFFBUS..2
R 2
(-950 3550);
FORCEPROP 1 LAST PART_NUMBER SP_CH4221MEE01
J 2
(-1066 3638);
DISPLAY 0.574468 (-1066 3638);
PAINT GREEN (-1066 3638);
DISPLAY INVISIBLE (-1066 3638);
FORCEPROP 2 LAST VALUE DIFF BUS_0.22UF
J 2
(-1100 3550);
DISPLAY 0.553191 (-1100 3550);
FORCEPROP 1 LAST $LOCATION C711
J 2
(-716 3567);
DISPLAY 0.723404 (-716 3567);
PAINT GREEN (-716 3567);
FORCEPROP 2 LASTPIN (-875 3550) $PN 1
J 0
(-865 3560);
DISPLAY 0.808511 (-865 3560);
FORCEPROP 2 LASTPIN (-1025 3550) $PN 2
J 2
(-1035 3560);
DISPLAY 0.808511 (-1035 3560);
FORCEPROP 1 LAST CDS_LMAN_SYM_OUTLINE -25,50,25,-50
J 2
(-950 3550);
DISPLAY 0.468085 (-950 3550);
PAINT GREEN (-950 3550);
DISPLAY INVISIBLE (-950 3550);
FORCEPROP 2 LAST CDS_LIB pure_quanta
J 2
(-950 3550);
DISPLAY INVISIBLE (-950 3550);
FORCEPROP 1 LAST PIN_NAMES_ROTATE TRUE
J 2
(-950 3550);
DISPLAY 0.489362 (-950 3550);
PAINT GREEN (-950 3550);
DISPLAY INVISIBLE (-950 3550);
FORCEPROP 2 LAST VOLTAGE 6.3V
J 2
(-1300 3600);
DISPLAY 0.553191 (-1300 3600);
DISPLAY INVISIBLE (-1300 3600);
FORCEPROP 1 LAST MATERIAL X6S
J 2
(-941 3629);
DISPLAY 0.574468 (-941 3629);
PAINT GREEN (-941 3629);
DISPLAY INVISIBLE (-941 3629);
FORCEPROP 2 LAST PACK_TYPE C0201
J 2
(-1125 3600);
DISPLAY 0.553191 (-1125 3600);
DISPLAY INVISIBLE (-1125 3600);
FORCEPROP 2 LAST TOLERANCE 20%
J 2
(-1025 3600);
DISPLAY 0.553191 (-1025 3600);
DISPLAY INVISIBLE (-1025 3600);
FORCEPROP 1 LAST PATH I298
J 2
(-950 3550);
DISPLAY 0.723404 (-950 3550);
DISPLAY INVISIBLE (-950 3550);
FORCEPROP 1 LAST $LOCATION C711
J 0
(-700 3625);
DISPLAY 1.021277 (-700 3625);
DISPLAY INVISIBLE (-700 3625);
FORCEPROP 2 LAST CDS_LOCATION C711
J 0
(-700 3625);
DISPLAY 1.021277 (-700 3625);
DISPLAY INVISIBLE (-700 3625);
FORCEPROP 2 LAST $SEC 1
J 2
(-775 3625);
DISPLAY 0.680851 (-775 3625);
PAINT MONO (-775 3625);
DISPLAY INVISIBLE (-775 3625);
FORCEPROP 2 LAST CDS_SEC 1
J 2
(-775 3625);
DISPLAY 0.680851 (-775 3625);
DISPLAY INVISIBLE (-775 3625);
FORCEADD Q_CAP_DIFFBUS..2
R 2
(-950 3600);
FORCEPROP 1 LAST PART_NUMBER SP_CH4221MEE01
J 2
(-766 3688);
DISPLAY 0.574468 (-766 3688);
PAINT GREEN (-766 3688);
DISPLAY INVISIBLE (-766 3688);
FORCEPROP 2 LAST VOLTAGE 6.3V
J 2
(-775 3750);
DISPLAY 0.553191 (-775 3750);
PAINT GREEN (-775 3750);
FORCEPROP 2 LAST TOLERANCE 20%
J 2
(-900 3750);
DISPLAY 0.553191 (-900 3750);
PAINT GREEN (-900 3750);
FORCEPROP 2 LAST VALUE DIFF BUS_0.22UF
J 2
(-1100 3600);
DISPLAY 0.553191 (-1100 3600);
FORCEPROP 2 LAST PACK_TYPE C0201
J 2
(-1000 3750);
DISPLAY 0.553191 (-1000 3750);
PAINT GREEN (-1000 3750);
FORCEPROP 1 LAST MATERIAL X6S
J 2
(-1041 3804);
DISPLAY 0.574468 (-1041 3804);
PAINT GREEN (-1041 3804);
FORCEPROP 1 LAST $LOCATION C710
J 2
(-716 3617);
DISPLAY 0.723404 (-716 3617);
PAINT GREEN (-716 3617);
FORCEPROP 2 LASTPIN (-875 3600) $PN 1
J 0
(-865 3610);
DISPLAY 0.808511 (-865 3610);
FORCEPROP 2 LASTPIN (-1025 3600) $PN 2
J 2
(-1035 3610);
DISPLAY 0.808511 (-1035 3610);
FORCEPROP 2 LAST CDS_LIB pure_quanta
J 2
(-950 3600);
DISPLAY INVISIBLE (-950 3600);
FORCEPROP 1 LAST CDS_LMAN_SYM_OUTLINE -25,50,25,-50
J 2
(-950 3600);
DISPLAY 0.468085 (-950 3600);
PAINT GREEN (-950 3600);
DISPLAY INVISIBLE (-950 3600);
FORCEPROP 1 LAST PIN_NAMES_ROTATE TRUE
J 2
(-950 3600);
DISPLAY 0.489362 (-950 3600);
PAINT GREEN (-950 3600);
DISPLAY INVISIBLE (-950 3600);
FORCEPROP 1 LAST PATH I299
J 2
(-950 3600);
DISPLAY 0.723404 (-950 3600);
DISPLAY INVISIBLE (-950 3600);
FORCEPROP 1 LAST $LOCATION C710
J 0
(-700 3675);
DISPLAY 1.021277 (-700 3675);
DISPLAY INVISIBLE (-700 3675);
FORCEPROP 2 LAST CDS_LOCATION C710
J 0
(-1025 3850);
DISPLAY 1.021277 (-1025 3850);
DISPLAY INVISIBLE (-1025 3850);
FORCEPROP 2 LAST $SEC 1
J 2
(-775 3675);
DISPLAY 0.680851 (-775 3675);
PAINT MONO (-775 3675);
DISPLAY INVISIBLE (-775 3675);
FORCEPROP 2 LAST CDS_SEC 1
J 2
(-775 3675);
DISPLAY 0.680851 (-775 3675);
DISPLAY INVISIBLE (-775 3675);
FORCEADD TAP..1
(-400 3200);
FORCEPROP 3 LASTPIN (-450 3200) SIG_NAME P5E_CPU1_PE0_TX_C_DN<13>
J 0
(-440 3210);
DISPLAY 0.659574 (-440 3210);
PAINT MONO (-440 3210);
DISPLAY INVISIBLE (-440 3210);
FORCEPROP 1 LASTPIN (-450 3200) BN 13
J 0
(-462 3208);
DISPLAY 0.680851 (-462 3208);
PAINT GREEN (-462 3208);
FORCEPROP 2 LAST CDS_LIB standard
J 0
(-400 3200);
DISPLAY INVISIBLE (-400 3200);
FORCEPROP 1 LAST BODY_TYPE PLUMBING
J 0
(-400 3250);
DISPLAY 0.872340 (-400 3250);
PAINT GREEN (-400 3250);
DISPLAY INVISIBLE (-400 3250);
FORCEPROP 1 LAST HDL_TAP TRUE
J 0
(-75 3075);
DISPLAY 0.872340 (-75 3075);
DISPLAY INVISIBLE (-75 3075);
FORCEPROP 1 LAST PATH I300
J 0
(-402 3200);
DISPLAY 0.872340 (-402 3200);
PAINT GREEN (-402 3200);
DISPLAY INVISIBLE (-402 3200);
FORCEADD TAP..1
(-400 3400);
FORCEPROP 3 LASTPIN (-450 3400) SIG_NAME P5E_CPU1_PE0_TX_C_DN<14>
J 0
(-440 3410);
DISPLAY 0.659574 (-440 3410);
PAINT MONO (-440 3410);
DISPLAY INVISIBLE (-440 3410);
FORCEPROP 1 LASTPIN (-450 3400) BN 14
J 0
(-462 3408);
DISPLAY 0.680851 (-462 3408);
PAINT GREEN (-462 3408);
FORCEPROP 2 LAST CDS_LIB standard
J 0
(-400 3400);
DISPLAY INVISIBLE (-400 3400);
FORCEPROP 1 LAST BODY_TYPE PLUMBING
J 0
(-400 3450);
DISPLAY 0.872340 (-400 3450);
PAINT GREEN (-400 3450);
DISPLAY INVISIBLE (-400 3450);
FORCEPROP 1 LAST HDL_TAP TRUE
J 0
(-75 3275);
DISPLAY 0.872340 (-75 3275);
DISPLAY INVISIBLE (-75 3275);
FORCEPROP 1 LAST PATH I301
J 0
(-402 3400);
DISPLAY 0.872340 (-402 3400);
PAINT GREEN (-402 3400);
DISPLAY INVISIBLE (-402 3400);
FORCEADD TAP..1
(-200 3150);
FORCEPROP 3 LASTPIN (-250 3150) SIG_NAME P5E_CPU1_PE0_TX_C_DP<13>
J 0
(-240 3160);
DISPLAY 0.659574 (-240 3160);
PAINT MONO (-240 3160);
DISPLAY INVISIBLE (-240 3160);
FORCEPROP 1 LASTPIN (-250 3150) BN 13
J 0
(-262 3158);
DISPLAY 0.680851 (-262 3158);
PAINT GREEN (-262 3158);
FORCEPROP 2 LAST CDS_LIB standard
J 0
(-200 3150);
DISPLAY INVISIBLE (-200 3150);
FORCEPROP 1 LAST BODY_TYPE PLUMBING
J 0
(-200 3200);
DISPLAY 0.872340 (-200 3200);
PAINT GREEN (-200 3200);
DISPLAY INVISIBLE (-200 3200);
FORCEPROP 1 LAST HDL_TAP TRUE
J 0
(125 3025);
DISPLAY 0.872340 (125 3025);
DISPLAY INVISIBLE (125 3025);
FORCEPROP 1 LAST PATH I302
J 0
(-202 3150);
DISPLAY 0.872340 (-202 3150);
PAINT GREEN (-202 3150);
DISPLAY INVISIBLE (-202 3150);
FORCEADD TAP..1
(-200 3350);
FORCEPROP 3 LASTPIN (-250 3350) SIG_NAME P5E_CPU1_PE0_TX_C_DP<14>
J 0
(-240 3360);
DISPLAY 0.659574 (-240 3360);
PAINT MONO (-240 3360);
DISPLAY INVISIBLE (-240 3360);
FORCEPROP 1 LASTPIN (-250 3350) BN 14
J 0
(-262 3358);
DISPLAY 0.680851 (-262 3358);
PAINT GREEN (-262 3358);
FORCEPROP 2 LAST CDS_LIB standard
J 0
(-200 3350);
DISPLAY INVISIBLE (-200 3350);
FORCEPROP 1 LAST BODY_TYPE PLUMBING
J 0
(-200 3400);
DISPLAY 0.872340 (-200 3400);
PAINT GREEN (-200 3400);
DISPLAY INVISIBLE (-200 3400);
FORCEPROP 1 LAST HDL_TAP TRUE
J 0
(125 3225);
DISPLAY 0.872340 (125 3225);
DISPLAY INVISIBLE (125 3225);
FORCEPROP 1 LAST PATH I303
J 0
(-202 3350);
DISPLAY 0.872340 (-202 3350);
PAINT GREEN (-202 3350);
DISPLAY INVISIBLE (-202 3350);
FORCEADD TAP..1
(-200 3550);
FORCEPROP 3 LASTPIN (-250 3550) SIG_NAME P5E_CPU1_PE0_TX_C_DP<15>
J 0
(-240 3560);
DISPLAY 0.659574 (-240 3560);
PAINT MONO (-240 3560);
DISPLAY INVISIBLE (-240 3560);
FORCEPROP 1 LASTPIN (-250 3550) BN 15
J 0
(-262 3558);
DISPLAY 0.680851 (-262 3558);
PAINT GREEN (-262 3558);
FORCEPROP 2 LAST CDS_LIB standard
J 0
(-200 3550);
DISPLAY INVISIBLE (-200 3550);
FORCEPROP 1 LAST BODY_TYPE PLUMBING
J 0
(-200 3600);
DISPLAY 0.872340 (-200 3600);
PAINT GREEN (-200 3600);
DISPLAY INVISIBLE (-200 3600);
FORCEPROP 1 LAST HDL_TAP TRUE
J 0
(125 3425);
DISPLAY 0.872340 (125 3425);
DISPLAY INVISIBLE (125 3425);
FORCEPROP 1 LAST PATH I304
J 0
(-202 3550);
DISPLAY 0.872340 (-202 3550);
PAINT GREEN (-202 3550);
DISPLAY INVISIBLE (-202 3550);
FORCEADD TAP..1
(-400 3600);
FORCEPROP 3 LASTPIN (-450 3600) SIG_NAME P5E_CPU1_PE0_TX_C_DN<15>
J 0
(-440 3610);
DISPLAY 0.659574 (-440 3610);
PAINT MONO (-440 3610);
DISPLAY INVISIBLE (-440 3610);
FORCEPROP 1 LASTPIN (-450 3600) BN 15
J 0
(-462 3608);
DISPLAY 0.680851 (-462 3608);
PAINT GREEN (-462 3608);
FORCEPROP 2 LAST CDS_LIB standard
J 0
(-400 3600);
DISPLAY INVISIBLE (-400 3600);
FORCEPROP 1 LAST BODY_TYPE PLUMBING
J 0
(-400 3650);
DISPLAY 0.872340 (-400 3650);
PAINT GREEN (-400 3650);
DISPLAY INVISIBLE (-400 3650);
FORCEPROP 1 LAST HDL_TAP TRUE
J 0
(-75 3475);
DISPLAY 0.872340 (-75 3475);
DISPLAY INVISIBLE (-75 3475);
FORCEPROP 1 LAST PATH I305
J 0
(-402 3600);
DISPLAY 0.872340 (-402 3600);
PAINT GREEN (-402 3600);
DISPLAY INVISIBLE (-402 3600);
FORCEADD OFFPAGE..2
(800 1600);
FORCEPROP 2 LAST $XR0 142 
J 0
(989 1600);
DISPLAY 0.638298 (989 1600);
PAINT MONO (989 1600);
FORCEPROP 2 LAST CDS_LIB standard
J 0
(800 1600);
DISPLAY INVISIBLE (800 1600);
FORCEPROP 1 LAST OFFPAGE TRUE
J 0
(1125 1475);
DISPLAY 0.872340 (1125 1475);
DISPLAY INVISIBLE (1125 1475);
FORCEPROP 1 LAST COMMENT_BODY TRUE
J 0
(755 1505);
DISPLAY 0.872340 (755 1505);
PAINT GREEN (755 1505);
DISPLAY INVISIBLE (755 1505);
FORCEPROP 2 LAST PATH I306
J 0
(1000 1650);
DISPLAY 1.021277 (1000 1650);
DISPLAY INVISIBLE (1000 1650);
FORCEADD OFFPAGE..2
(800 1650);
FORCEPROP 2 LAST $XR0 142 
J 0
(989 1650);
DISPLAY 0.638298 (989 1650);
PAINT MONO (989 1650);
FORCEPROP 2 LAST CDS_LIB standard
J 0
(800 1650);
DISPLAY INVISIBLE (800 1650);
FORCEPROP 1 LAST OFFPAGE TRUE
J 0
(1125 1525);
DISPLAY 0.872340 (1125 1525);
DISPLAY INVISIBLE (1125 1525);
FORCEPROP 1 LAST COMMENT_BODY TRUE
J 0
(755 1555);
DISPLAY 0.872340 (755 1555);
PAINT GREEN (755 1555);
DISPLAY INVISIBLE (755 1555);
FORCEPROP 2 LAST PATH I307
J 0
(1000 1700);
DISPLAY 1.021277 (1000 1700);
DISPLAY INVISIBLE (1000 1700);
FORCEADD OFFPAGE..2
(800 3575);
FORCEPROP 2 LAST $XR0 143 
J 0
(989 3575);
DISPLAY 0.638298 (989 3575);
PAINT MONO (989 3575);
FORCEPROP 2 LAST CDS_LIB standard
J 0
(800 3575);
DISPLAY INVISIBLE (800 3575);
FORCEPROP 1 LAST OFFPAGE TRUE
J 0
(1125 3450);
DISPLAY 0.872340 (1125 3450);
DISPLAY INVISIBLE (1125 3450);
FORCEPROP 1 LAST COMMENT_BODY TRUE
J 0
(755 3480);
DISPLAY 0.872340 (755 3480);
PAINT GREEN (755 3480);
DISPLAY INVISIBLE (755 3480);
FORCEPROP 2 LAST PATH I308
J 0
(1000 3625);
DISPLAY 1.021277 (1000 3625);
DISPLAY INVISIBLE (1000 3625);
FORCEADD OFFPAGE..2
(800 3625);
FORCEPROP 2 LAST $XR0 143 
J 0
(989 3625);
DISPLAY 0.638298 (989 3625);
PAINT MONO (989 3625);
FORCEPROP 2 LAST CDS_LIB standard
J 0
(800 3625);
DISPLAY INVISIBLE (800 3625);
FORCEPROP 1 LAST OFFPAGE TRUE
J 0
(1125 3500);
DISPLAY 0.872340 (1125 3500);
DISPLAY INVISIBLE (1125 3500);
FORCEPROP 1 LAST COMMENT_BODY TRUE
J 0
(755 3530);
DISPLAY 0.872340 (755 3530);
PAINT GREEN (755 3530);
DISPLAY INVISIBLE (755 3530);
FORCEPROP 2 LAST PATH I309
J 0
(1000 3675);
DISPLAY 1.021277 (1000 3675);
DISPLAY INVISIBLE (1000 3675);
FORCEADD TAP..1
(-200 975);
FORCEPROP 3 LASTPIN (-250 975) SIG_NAME P5E_CPU1_PE0_TX_C_DP<4>
J 0
(-240 985);
DISPLAY 0.659574 (-240 985);
PAINT MONO (-240 985);
DISPLAY INVISIBLE (-240 985);
FORCEPROP 1 LASTPIN (-250 975) BN 4
J 0
(-262 983);
DISPLAY 0.680851 (-262 983);
PAINT GREEN (-262 983);
FORCEPROP 2 LAST CDS_LIB standard
J 0
(-200 975);
DISPLAY INVISIBLE (-200 975);
FORCEPROP 1 LAST BODY_TYPE PLUMBING
J 0
(-200 1025);
DISPLAY 0.872340 (-200 1025);
PAINT GREEN (-200 1025);
DISPLAY INVISIBLE (-200 1025);
FORCEPROP 1 LAST HDL_TAP TRUE
J 0
(125 850);
DISPLAY 0.872340 (125 850);
DISPLAY INVISIBLE (125 850);
FORCEPROP 1 LAST PATH I310
J 0
(-202 975);
DISPLAY 0.872340 (-202 975);
PAINT GREEN (-202 975);
DISPLAY INVISIBLE (-202 975);
FORCEADD TAP..1
(-400 1225);
FORCEPROP 3 LASTPIN (-450 1225) SIG_NAME P5E_CPU1_PE0_TX_C_DN<5>
J 0
(-440 1235);
DISPLAY 0.659574 (-440 1235);
PAINT MONO (-440 1235);
DISPLAY INVISIBLE (-440 1235);
FORCEPROP 1 LASTPIN (-450 1225) BN 5
J 0
(-462 1233);
DISPLAY 0.680851 (-462 1233);
PAINT GREEN (-462 1233);
FORCEPROP 2 LAST CDS_LIB standard
J 0
(-400 1225);
DISPLAY INVISIBLE (-400 1225);
FORCEPROP 1 LAST BODY_TYPE PLUMBING
J 0
(-400 1275);
DISPLAY 0.872340 (-400 1275);
PAINT GREEN (-400 1275);
DISPLAY INVISIBLE (-400 1275);
FORCEPROP 1 LAST HDL_TAP TRUE
J 0
(-75 1100);
DISPLAY 0.872340 (-75 1100);
DISPLAY INVISIBLE (-75 1100);
FORCEPROP 1 LAST PATH I311
J 0
(-402 1225);
DISPLAY 0.872340 (-402 1225);
PAINT GREEN (-402 1225);
DISPLAY INVISIBLE (-402 1225);
FORCEADD Q_CAP_DIFFBUS..2
R 2
(-950 1625);
FORCEPROP 1 LAST PART_NUMBER SP_CH4221MEE01
J 2
(-1066 1713);
DISPLAY 0.574468 (-1066 1713);
PAINT GREEN (-1066 1713);
DISPLAY INVISIBLE (-1066 1713);
FORCEPROP 2 LAST VALUE DIFF BUS_0.22UF
J 2
(-1100 1625);
DISPLAY 0.553191 (-1100 1625);
FORCEPROP 1 LAST $LOCATION C726
J 2
(-716 1642);
DISPLAY 0.723404 (-716 1642);
PAINT GREEN (-716 1642);
FORCEPROP 2 LASTPIN (-875 1625) $PN 1
J 0
(-865 1635);
DISPLAY 0.808511 (-865 1635);
FORCEPROP 2 LASTPIN (-1025 1625) $PN 2
J 2
(-1035 1635);
DISPLAY 0.808511 (-1035 1635);
FORCEPROP 1 LAST PIN_NAMES_ROTATE TRUE
J 2
(-950 1625);
DISPLAY 0.489362 (-950 1625);
PAINT GREEN (-950 1625);
DISPLAY INVISIBLE (-950 1625);
FORCEPROP 1 LAST CDS_LMAN_SYM_OUTLINE -25,50,25,-50
J 2
(-950 1625);
DISPLAY 0.468085 (-950 1625);
PAINT GREEN (-950 1625);
DISPLAY INVISIBLE (-950 1625);
FORCEPROP 2 LAST CDS_LIB pure_quanta
J 2
(-950 1625);
DISPLAY INVISIBLE (-950 1625);
FORCEPROP 2 LAST VOLTAGE 6.3V
J 2
(-1300 1675);
DISPLAY 0.553191 (-1300 1675);
DISPLAY INVISIBLE (-1300 1675);
FORCEPROP 1 LAST MATERIAL X6S
J 2
(-941 1704);
DISPLAY 0.574468 (-941 1704);
PAINT GREEN (-941 1704);
DISPLAY INVISIBLE (-941 1704);
FORCEPROP 2 LAST PACK_TYPE C0201
J 2
(-1125 1675);
DISPLAY 0.553191 (-1125 1675);
DISPLAY INVISIBLE (-1125 1675);
FORCEPROP 2 LAST TOLERANCE 20%
J 2
(-1025 1675);
DISPLAY 0.553191 (-1025 1675);
DISPLAY INVISIBLE (-1025 1675);
FORCEPROP 1 LAST PATH I312
J 2
(-950 1625);
DISPLAY 0.723404 (-950 1625);
DISPLAY INVISIBLE (-950 1625);
FORCEPROP 1 LAST $LOCATION C726
J 0
(-700 1700);
DISPLAY 1.021277 (-700 1700);
DISPLAY INVISIBLE (-700 1700);
FORCEPROP 2 LAST CDS_LOCATION C726
J 0
(-700 1700);
DISPLAY 1.021277 (-700 1700);
DISPLAY INVISIBLE (-700 1700);
FORCEPROP 2 LAST $SEC 1
J 2
(-775 1700);
DISPLAY 0.680851 (-775 1700);
PAINT MONO (-775 1700);
DISPLAY INVISIBLE (-775 1700);
FORCEPROP 2 LAST CDS_SEC 1
J 2
(-775 1700);
DISPLAY 0.680851 (-775 1700);
DISPLAY INVISIBLE (-775 1700);
FORCEADD OFFPAGE..1
(1700 1675);
FORCEPROP 2 LAST $XR0 61 
J 0
(1479 1675);
DISPLAY 0.638298 (1479 1675);
PAINT MONO (1479 1675);
FORCEPROP 2 LAST CDS_LIB standard
J 0
(1700 1675);
DISPLAY INVISIBLE (1700 1675);
FORCEPROP 1 LAST OFFPAGE TRUE
J 0
(2025 1550);
DISPLAY 0.872340 (2025 1550);
DISPLAY INVISIBLE (2025 1550);
FORCEPROP 1 LAST COMMENT_BODY TRUE
J 0
(1825 1575);
DISPLAY 0.872340 (1825 1575);
PAINT GREEN (1825 1575);
DISPLAY INVISIBLE (1825 1575);
FORCEPROP 2 LAST PATH I95
J 0
(1750 1750);
DISPLAY 1.021277 (1750 1750);
DISPLAY INVISIBLE (1750 1750);
FORCEADD OFFPAGE..1
(1700 1625);
FORCEPROP 2 LAST $XR0 61 
J 0
(1479 1625);
DISPLAY 0.638298 (1479 1625);
PAINT MONO (1479 1625);
FORCEPROP 2 LAST CDS_LIB standard
J 0
(1700 1625);
DISPLAY INVISIBLE (1700 1625);
FORCEPROP 1 LAST OFFPAGE TRUE
J 0
(2025 1500);
DISPLAY 0.872340 (2025 1500);
DISPLAY INVISIBLE (2025 1500);
FORCEPROP 1 LAST COMMENT_BODY TRUE
J 0
(1825 1525);
DISPLAY 0.872340 (1825 1525);
PAINT GREEN (1825 1525);
DISPLAY INVISIBLE (1825 1525);
FORCEPROP 2 LAST PATH I96
J 0
(1750 1700);
DISPLAY 1.021277 (1750 1700);
DISPLAY INVISIBLE (1750 1700);
FORCEADD QUANTA_TITLE_BLOCK_C..1
(5875 -1650);
FORCEPROP 0 LAST CDS_CON_LAST_MODIFIED Fri Aug 25 14:02:47 2023
J 0
(3990 -1635);
DISPLAY INVISIBLE (3990 -1635);
FORCEPROP 1 LAST CUSTOM_TXT_CDS <CON_LAST_MODIFIED>
J 0
(3990 -1635);
DISPLAY 0.978723 (3990 -1635);
FORCEPROP 2 LAST CUSTOM_TXT_CDS <XR_PAGE_TITLE>
J 0
(-2015 3600);
DISPLAY 0.638298 (-2015 3600);
PAINT PINK (-2015 3600);
DISPLAY INVISIBLE (-2015 3600);
FORCEPROP 2 LAST CUSTOM_TXT_CDS <CON_PAGE_NUM> OF <CON_TOTAL_PAGES>
J 0
(5429 -1632);
DISPLAY 0.978723 (5429 -1632);
FORCEPROP 2 LAST CUSTOM_TXT_CDS <Q_NUMBER>
J 0
(4472 -1547);
DISPLAY 1.212766 (4472 -1547);
FORCEPROP 2 LAST CUSTOM_TXT_CDS <Q_PROJ>
J 0
(3493 -1548);
DISPLAY 1.212766 (3493 -1548);
FORCEPROP 2 LAST CUSTOM_TXT_CDS <Q_REV>
J 0
(5691 -1547);
DISPLAY 1.212766 (5691 -1547);
FORCEPROP 1 LAST CUSTOM_TXT_CDS <NAME_2>
J 0
(2700 -1600);
FORCEPROP 1 LAST CUSTOM_TXT_CDS <NAME_1>
J 0
(2700 -1475);
FORCEPROP 1 LAST Q_TITLE PCIE AC-COUPLE CAPS 4/5
J 0
(-3491 -1624);
DISPLAY 2.446809 (-3491 -1624);
PAINT GREEN (-3491 -1624);
FORCEPROP 1 LAST Q_DEPT 
J 1
(2112 -1601);
DISPLAY 1.957447 (2112 -1601);
PAINT GREEN (2112 -1601);
FORCEPROP 2 LAST CDS_XR_PAGE_TITLE CR-176 : @S9S_MB_2U_LIB.S9S_MB_2U(SCH_1):PAGE176
J 0
(-2015 3600);
DISPLAY 0.638298 (-2015 3600);
PAINT PINK (-2015 3600);
DISPLAY INVISIBLE (-2015 3600);
FORCEPROP 2 LAST PAGE_BORDER TRUE
J 0
(-2015 3600);
DISPLAY 0.638298 (-2015 3600);
PAINT PINK (-2015 3600);
DISPLAY INVISIBLE (-2015 3600);
FORCEPROP 1 LAST COMMENT_BODY TRUE
J 0
(5887 -1663);
DISPLAY 0.978723 (5887 -1663);
PAINT GREEN (5887 -1663);
DISPLAY INVISIBLE (5887 -1663);
FORCEPROP 1 LAST CDS_LMAN_SYM_OUTLINE -9475,6775,100,-125
J 0
(5875 -1650);
DISPLAY 0.468085 (5875 -1650);
PAINT GREEN (5875 -1650);
DISPLAY INVISIBLE (5875 -1650);
FORCEPROP 2 LAST CDS_LIB pure_quanta
J 0
(5875 -1650);
DISPLAY INVISIBLE (5875 -1650);
WIRE 17 -1 (2850 1475)(2850 1275);
WIRE 17 -1 (2850 1675)(2850 1475);
WIRE 17 -1 (2850 1275)(2850 1075);
WIRE 17 -1 (2850 875)(2850 1075);
WIRE 17 -1 (1750 1675)(2850 1675);
FORCEPROP 2 LAST SIG_NAME P5E_CPU1_PE2_TX_DN<7:0>
J 0
(1790 1685);
DISPLAY 0.680851 (1790 1685);
PAINT WHITE (1790 1685);
WIRE 17 -1 (2850 875)(2850 675);
WIRE 17 -1 (2850 675)(2850 475);
WIRE 17 -1 (2850 475)(2850 275);
WIRE 17 -1 (2600 425)(2600 625);
WIRE 17 -1 (2600 225)(2600 425);
WIRE 17 -1 (2600 625)(2600 825);
WIRE 17 -1 (2600 825)(2600 1025);
WIRE 17 -1 (2600 1025)(2600 1225);
WIRE 17 -1 (2600 1225)(2600 1425);
WIRE 17 -1 (2600 1425)(2600 1625);
WIRE 17 -1 (1750 1625)(2600 1625);
FORCEPROP 2 LAST SIG_NAME P5E_CPU1_PE2_TX_DP<7:0>
J 0
(1790 1635);
DISPLAY 0.680851 (1790 1635);
PAINT WHITE (1790 1635);
WIRE 17 -1 (2850 3650)(2850 3450);
WIRE 17 -1 (1750 3650)(2850 3650);
FORCEPROP 2 LAST SIG_NAME P5E_CPU1_PE2_TX_DN<15:8>
J 0
(1790 3660);
DISPLAY 0.680851 (1790 3660);
PAINT WHITE (1790 3660);
WIRE 17 -1 (2850 3450)(2850 3250);
WIRE 17 -1 (2850 3250)(2850 3050);
WIRE 17 -1 (2850 2850)(2850 3050);
WIRE 17 -1 (2850 2850)(2850 2650);
WIRE 17 -1 (2850 2650)(2850 2450);
WIRE 17 -1 (2850 2450)(2850 2250);
WIRE 17 -1 (2600 2200)(2600 2400);
WIRE 17 -1 (2600 2400)(2600 2600);
WIRE 17 -1 (2600 2600)(2600 2800);
WIRE 17 -1 (2600 2800)(2600 3000);
WIRE 17 -1 (2600 3000)(2600 3200);
WIRE 17 -1 (2600 3200)(2600 3400);
WIRE 17 -1 (2600 3400)(2600 3600);
WIRE 17 -1 (1750 3600)(2600 3600);
FORCEPROP 2 LAST SIG_NAME P5E_CPU1_PE2_TX_DP<15:8>
J 0
(1790 3610);
DISPLAY 0.680851 (1790 3610);
PAINT WHITE (1790 3610);
WIRE 17 -1 (4225 875)(4225 1075);
WIRE 17 -1 (4225 875)(4225 675);
WIRE 17 -1 (4225 1275)(4225 1075);
WIRE 17 -1 (4225 1475)(4225 1275);
WIRE 17 -1 (4225 675)(4225 475);
WIRE 17 -1 (4225 475)(4225 275);
WIRE 17 -1 (4225 1675)(4225 1475);
WIRE 17 -1 (4225 1675)(5325 1675);
FORCEPROP 2 LAST SIG_NAME P5E_CPU1_PE2_TX_C_DN<7:0>
J 0
(4465 1685);
DISPLAY 0.680851 (4465 1685);
PAINT WHITE (4465 1685);
WIRE 17 -1 (4425 825)(4425 1025);
WIRE 17 -1 (4425 825)(4425 625);
WIRE 17 -1 (4425 1225)(4425 1025);
WIRE 17 -1 (4425 1425)(4425 1225);
WIRE 17 -1 (4425 625)(4425 425);
WIRE 17 -1 (4425 425)(4425 225);
WIRE 17 -1 (4425 1625)(4425 1425);
WIRE 17 -1 (4425 1625)(5325 1625);
FORCEPROP 2 LAST SIG_NAME P5E_CPU1_PE2_TX_C_DP<7:0>
J 0
(4465 1635);
DISPLAY 0.680851 (4465 1635);
PAINT WHITE (4465 1635);
WIRE 17 -1 (4225 2650)(4225 2450);
WIRE 17 -1 (4225 2850)(4225 2650);
WIRE 17 -1 (4225 2450)(4225 2250);
WIRE 17 -1 (4225 2850)(4225 3050);
WIRE 17 -1 (4225 3250)(4225 3050);
WIRE 17 -1 (4225 3450)(4225 3250);
WIRE 17 -1 (4225 3650)(4225 3450);
WIRE 17 -1 (4225 3650)(5325 3650);
FORCEPROP 2 LAST SIG_NAME P5E_CPU1_PE2_TX_C_DN<15:8>
J 0
(4465 3660);
DISPLAY 0.680851 (4465 3660);
PAINT WHITE (4465 3660);
WIRE 17 -1 (4425 2400)(4425 2200);
WIRE 17 -1 (4425 2600)(4425 2400);
WIRE 17 -1 (4425 2800)(4425 2600);
WIRE 17 -1 (4425 2800)(4425 3000);
WIRE 17 -1 (4425 3200)(4425 3000);
WIRE 17 -1 (4425 3400)(4425 3200);
WIRE 17 -1 (4425 3600)(4425 3400);
WIRE 17 -1 (4425 3600)(5325 3600);
FORCEPROP 2 LAST SIG_NAME P5E_CPU1_PE2_TX_C_DP<15:8>
J 0
(4465 3610);
DISPLAY 0.680851 (4465 3610);
PAINT WHITE (4465 3610);
WIRE 17 -1 (-1725 850)(-1725 650);
WIRE 17 -1 (-1725 850)(-1725 1050);
WIRE 17 -1 (-1725 650)(-1725 450);
WIRE 17 -1 (-1725 450)(-1725 250);
WIRE 17 -1 (-1725 1250)(-1725 1050);
WIRE 17 -1 (-1725 1450)(-1725 1250);
WIRE 17 -1 (-1725 1650)(-1725 1450);
WIRE 17 -1 (-2825 1650)(-1725 1650);
FORCEPROP 2 LAST SIG_NAME P5E_CPU1_PE0_TX_DN<7:0>
J 0
(-2810 1660);
DISPLAY 0.680851 (-2810 1660);
PAINT WHITE (-2810 1660);
WIRE 17 -1 (-1975 200)(-1975 400);
WIRE 17 -1 (-1975 400)(-1975 600);
WIRE 17 -1 (-1975 600)(-1975 800);
WIRE 17 -1 (-1975 800)(-1975 1000);
WIRE 17 -1 (-1975 1000)(-1975 1200);
WIRE 17 -1 (-1975 1200)(-1975 1400);
WIRE 17 -1 (-1975 1400)(-1975 1600);
WIRE 17 -1 (-2825 1600)(-1975 1600);
FORCEPROP 2 LAST SIG_NAME P5E_CPU1_PE0_TX_DP<7:0>
J 0
(-2810 1610);
DISPLAY 0.680851 (-2810 1610);
PAINT WHITE (-2810 1610);
WIRE 17 -1 (-150 400)(-150 200);
WIRE 17 -1 (-150 600)(-150 400);
WIRE 17 -1 (-150 800)(-150 600);
WIRE 17 -1 (-150 800)(-150 1000);
WIRE 17 -1 (-150 1200)(-150 1000);
WIRE 17 -1 (-150 1400)(-150 1200);
WIRE 17 -1 (-150 1600)(-150 1400);
WIRE 17 -1 (-150 1600)(750 1600);
FORCEPROP 2 LAST SIG_NAME P5E_CPU1_PE0_TX_C_DP<7:0>
J 0
(-85 1610);
DISPLAY 0.680851 (-85 1610);
PAINT WHITE (-85 1610);
WIRE 17 -1 (-350 850)(-350 650);
WIRE 17 -1 (-350 850)(-350 1050);
WIRE 17 -1 (-350 650)(-350 450);
WIRE 17 -1 (-350 450)(-350 250);
WIRE 17 -1 (-350 1250)(-350 1050);
WIRE 17 -1 (-350 1450)(-350 1250);
WIRE 17 -1 (-350 1650)(-350 1450);
WIRE 17 -1 (-350 1650)(750 1650);
FORCEPROP 2 LAST SIG_NAME P5E_CPU1_PE0_TX_C_DN<7:0>
J 0
(-85 1660);
DISPLAY 0.680851 (-85 1660);
PAINT WHITE (-85 1660);
WIRE 17 -1 (-1725 2825)(-1725 2625);
WIRE 17 -1 (-1725 2825)(-1725 3025);
WIRE 17 -1 (-1725 2625)(-1725 2425);
WIRE 17 -1 (-1725 2425)(-1725 2225);
WIRE 17 -1 (-1725 3225)(-1725 3025);
WIRE 17 -1 (-1725 3425)(-1725 3225);
WIRE 17 -1 (-1725 3625)(-1725 3425);
WIRE 17 -1 (-2825 3625)(-1725 3625);
FORCEPROP 2 LAST SIG_NAME P5E_CPU1_PE0_TX_DN<15:8>
J 0
(-2810 3635);
DISPLAY 0.680851 (-2810 3635);
PAINT WHITE (-2810 3635);
WIRE 17 -1 (-1975 2375)(-1975 2575);
WIRE 17 -1 (-1975 2175)(-1975 2375);
WIRE 17 -1 (-1975 2575)(-1975 2775);
WIRE 17 -1 (-1975 2775)(-1975 2975);
WIRE 17 -1 (-1975 2975)(-1975 3175);
WIRE 17 -1 (-1975 3175)(-1975 3375);
WIRE 17 -1 (-1975 3375)(-1975 3575);
WIRE 17 -1 (-2825 3575)(-1975 3575);
FORCEPROP 2 LAST SIG_NAME P5E_CPU1_PE0_TX_DP<15:8>
J 0
(-2810 3585);
DISPLAY 0.680851 (-2810 3585);
PAINT WHITE (-2810 3585);
WIRE 17 -1 (-150 2775)(-150 2975);
WIRE 17 -1 (-150 2775)(-150 2575);
WIRE 17 -1 (-150 3175)(-150 2975);
WIRE 17 -1 (-150 3375)(-150 3175);
WIRE 17 -1 (-150 2575)(-150 2375);
WIRE 17 -1 (-150 2375)(-150 2175);
WIRE 17 -1 (-150 3575)(-150 3375);
WIRE 17 -1 (-150 3575)(750 3575);
FORCEPROP 2 LAST SIG_NAME P5E_CPU1_PE0_TX_C_DP<15:8>
J 0
(-85 3585);
DISPLAY 0.680851 (-85 3585);
PAINT WHITE (-85 3585);
WIRE 17 -1 (-350 2825)(-350 3025);
WIRE 17 -1 (-350 2825)(-350 2625);
WIRE 17 -1 (-350 3225)(-350 3025);
WIRE 17 -1 (-350 3425)(-350 3225);
WIRE 17 -1 (-350 2625)(-350 2425);
WIRE 17 -1 (-350 2425)(-350 2225);
WIRE 17 -1 (-350 3625)(-350 3425);
WIRE 17 -1 (-350 3625)(750 3625);
FORCEPROP 2 LAST SIG_NAME P5E_CPU1_PE0_TX_C_DN<15:8>
J 0
(-85 3635);
DISPLAY 0.680851 (-85 3635);
PAINT WHITE (-85 3635);
WIRE 16 -1 (-1025 3550)(-1875 3550);
WIRE 16 -1 (-1025 3400)(-1625 3400);
WIRE 16 -1 (-1025 3350)(-1875 3350);
WIRE 16 -1 (-1025 3150)(-1875 3150);
WIRE 16 -1 (-1025 3000)(-1625 3000);
WIRE 16 -1 (-1025 2950)(-1875 2950);
WIRE 16 -1 (-1025 2750)(-1875 2750);
WIRE 16 -1 (-1025 2400)(-1625 2400);
WIRE 16 -1 (-1025 1575)(-1875 1575);
WIRE 16 -1 (-1025 2150)(-1875 2150);
WIRE 16 -1 (-875 1575)(-250 1575);
WIRE 16 -1 (-875 1425)(-450 1425);
WIRE 16 -1 (-875 1375)(-250 1375);
WIRE 16 -1 (-875 1175)(-250 1175);
WIRE 16 -1 (-875 975)(-250 975);
WIRE 16 -1 (-875 3150)(-250 3150);
WIRE 16 -1 (-875 3550)(-250 3550);
WIRE 16 -1 (-875 3350)(-250 3350);
WIRE 16 -1 (-875 3600)(-450 3600);
WIRE 16 -1 (-875 3200)(-450 3200);
WIRE 16 -1 (-875 3400)(-450 3400);
WIRE 16 -1 (-875 2150)(-250 2150);
WIRE 16 -1 (-875 2550)(-250 2550);
WIRE 16 -1 (-875 2350)(-250 2350);
WIRE 16 -1 (-875 2750)(-250 2750);
WIRE 16 -1 (-875 2400)(-450 2400);
WIRE 16 -1 (-875 3000)(-450 3000);
WIRE 16 -1 (-875 2600)(-450 2600);
WIRE 16 -1 (-875 2200)(-450 2200);
WIRE 16 -1 (-875 2800)(-450 2800);
WIRE 16 -1 (-875 2950)(-250 2950);
WIRE 16 -1 (-1025 3200)(-1625 3200);
WIRE 16 -1 (-1025 3600)(-1625 3600);
WIRE 16 -1 (-1025 2200)(-1625 2200);
WIRE 16 -1 (-1025 2550)(-1875 2550);
WIRE 16 -1 (-1025 2350)(-1875 2350);
WIRE 16 -1 (-1025 2800)(-1625 2800);
WIRE 16 -1 (-1025 2600)(-1625 2600);
WIRE 16 -1 (-875 1225)(-450 1225);
WIRE 16 -1 (-875 1625)(-450 1625);
WIRE 16 -1 (-875 1025)(-450 1025);
WIRE 16 -1 (-875 775)(-250 775);
WIRE 16 -1 (-875 375)(-250 375);
WIRE 16 -1 (-875 825)(-450 825);
WIRE 16 -1 (-875 225)(-450 225);
WIRE 16 -1 (-875 425)(-450 425);
WIRE 16 -1 (-875 625)(-450 625);
WIRE 16 -1 (-875 575)(-250 575);
WIRE 16 -1 (-875 175)(-250 175);
WIRE 16 -1 (-1025 1425)(-1625 1425);
WIRE 16 -1 (-1025 1025)(-1625 1025);
WIRE 16 -1 (-1025 225)(-1625 225);
WIRE 16 -1 (-1025 825)(-1625 825);
WIRE 16 -1 (-1025 1375)(-1875 1375);
WIRE 16 -1 (-1025 1175)(-1875 1175);
WIRE 16 -1 (-1025 1225)(-1625 1225);
WIRE 16 -1 (-1025 375)(-1875 375);
WIRE 16 -1 (-1025 1625)(-1625 1625);
WIRE 16 -1 (-1025 425)(-1625 425);
WIRE 16 -1 (-1025 575)(-1875 575);
WIRE 16 -1 (-1025 775)(-1875 775);
WIRE 16 -1 (-1025 975)(-1875 975);
WIRE 16 -1 (-1025 175)(-1875 175);
WIRE 16 -1 (-1025 625)(-1625 625);
WIRE 16 -1 (3550 3375)(2700 3375);
WIRE 16 -1 (3700 3225)(4125 3225);
WIRE 16 -1 (3700 1400)(4325 1400);
WIRE 16 -1 (3550 1600)(2700 1600);
WIRE 16 -1 (3550 2775)(2700 2775);
WIRE 16 -1 (3550 3025)(2950 3025);
WIRE 16 -1 (3700 3025)(4125 3025);
WIRE 16 -1 (3700 2975)(4325 2975);
WIRE 16 -1 (3550 2975)(2700 2975);
WIRE 16 -1 (3550 800)(2700 800);
WIRE 16 -1 (3700 650)(4125 650);
WIRE 16 -1 (3700 2375)(4325 2375);
WIRE 16 -1 (3550 2375)(2700 2375);
WIRE 16 -1 (3700 2575)(4325 2575);
WIRE 16 -1 (3700 450)(4125 450);
WIRE 16 -1 (3550 1000)(2700 1000);
WIRE 16 -1 (3550 1050)(2950 1050);
WIRE 16 -1 (3550 2575)(2700 2575);
WIRE 16 -1 (3550 1400)(2700 1400);
WIRE 16 -1 (3550 1450)(2950 1450);
WIRE 16 -1 (3700 2775)(4325 2775);
WIRE 16 -1 (3700 250)(4125 250);
WIRE 16 -1 (3700 400)(4325 400);
WIRE 16 -1 (3700 3175)(4325 3175);
WIRE 16 -1 (3700 3375)(4325 3375);
WIRE 16 -1 (3700 3575)(4325 3575);
WIRE 16 -1 (3700 3625)(4125 3625);
WIRE 16 -1 (3700 3425)(4125 3425);
WIRE 16 -1 (3700 2175)(4325 2175);
WIRE 16 -1 (3700 2825)(4125 2825);
WIRE 16 -1 (3700 2625)(4125 2625);
WIRE 16 -1 (3700 2225)(4125 2225);
WIRE 16 -1 (3700 2425)(4125 2425);
WIRE 16 -1 (3700 1600)(4325 1600);
WIRE 16 -1 (3700 1200)(4325 1200);
WIRE 16 -1 (3700 1650)(4125 1650);
WIRE 16 -1 (3700 1450)(4125 1450);
WIRE 16 -1 (3700 1250)(4125 1250);
WIRE 16 -1 (3700 1050)(4125 1050);
WIRE 16 -1 (3700 200)(4325 200);
WIRE 16 -1 (3700 800)(4325 800);
WIRE 16 -1 (3700 600)(4325 600);
WIRE 16 -1 (3700 1000)(4325 1000);
WIRE 16 -1 (3700 850)(4125 850);
WIRE 16 -1 (3550 3575)(2700 3575);
WIRE 16 -1 (3550 3175)(2700 3175);
WIRE 16 -1 (3550 2175)(2700 2175);
WIRE 16 -1 (3550 2225)(2950 2225);
WIRE 16 -1 (3550 2825)(2950 2825);
WIRE 16 -1 (3550 2425)(2950 2425);
WIRE 16 -1 (3550 2625)(2950 2625);
WIRE 16 -1 (3550 3425)(2950 3425);
WIRE 16 -1 (3550 3225)(2950 3225);
WIRE 16 -1 (3550 3625)(2950 3625);
WIRE 16 -1 (3550 1200)(2700 1200);
WIRE 16 -1 (3550 200)(2700 200);
WIRE 16 -1 (3550 600)(2700 600);
WIRE 16 -1 (3550 400)(2700 400);
WIRE 16 -1 (3550 250)(2950 250);
WIRE 16 -1 (3550 850)(2950 850);
WIRE 16 -1 (3550 450)(2950 450);
WIRE 16 -1 (3550 650)(2950 650);
WIRE 16 -1 (3550 1650)(2950 1650);
WIRE 16 -1 (3550 1250)(2950 1250);
FORCENOTE
CPU1 PCIE0 TX
(-2275 -450) 0;
DISPLAY LEFT (-2275 -450);
DISPLAY 4.148936 (-2275 -450);
PAINT WHITE (-2275 -450);
FORCENOTE
CPU1 PCIE2 TX
(2350 -425) 0;
DISPLAY LEFT (2350 -425);
DISPLAY 4.148936 (2350 -425);
PAINT WHITE (2350 -425);
FORCENOTE
20210527 MODIFY FOR GT
(-2300 4250) 0;
DISPLAY LEFT (-2300 4250);
DISPLAY 2.510638 (-2300 4250);
PAINT PINK (-2300 4250);
QUIT
